FILE_TYPE = MACRO_DRAWING;
SET COLOR_WIRE YELLOW;
SET COLOR_PROP ORANGE;
SET COLOR_DOT WHITE;
SET COLOR_ARC YELLOW;
SET COLOR_BODY GREEN;
SET COLOR_NOTE PURPLE;
SET PROP_DISPLAY VALUE;
SET PAGE_NUMBER P23;
SET PATH_NUMBER P170;
FORCEADD OFFPAGE..1
(-1775 -775);
FORCEPROP 2 LAST $XR0 15 
J 0
(-1996 -775);
DISPLAY 0.638298 (-1996 -775);
PAINT MONO (-1996 -775);
FORCEPROP 2 LAST PATH I1
J 0
(-1950 -725);
DISPLAY 1.021277 (-1950 -725);
DISPLAY INVISIBLE (-1950 -725);
FORCEPROP 1 LAST COMMENT_BODY TRUE
J 0
(-1650 -875);
DISPLAY 1.319149 (-1650 -875);
PAINT PEACH (-1650 -875);
DISPLAY INVISIBLE (-1650 -875);
FORCEPROP 1 LAST OFFPAGE TRUE
J 0
(-1450 -900);
DISPLAY 1.340425 (-1450 -900);
PAINT GREEN (-1450 -900);
DISPLAY INVISIBLE (-1450 -900);
FORCEPROP 2 LAST ROOM SM_CONTROLLER
J 0
(-2050 -725);
DISPLAY 1.319149 (-2050 -725);
DISPLAY INVISIBLE (-2050 -725);
FORCEPROP 2 LAST CDS_LIB standard
J 0
(-1775 -775);
DISPLAY 2.085106 (-1775 -775);
DISPLAY INVISIBLE (-1775 -775);
FORCEADD UNIVERSAL_GND..1
(-2100 275);
FORCEPROP 3 LASTPIN (-2100 325) SIG_NAME GND\g
J 0
(-2090 335);
DISPLAY 0.659574 (-2090 335);
PAINT MONO (-2090 335);
DISPLAY INVISIBLE (-2090 335);
FORCEPROP 1 LAST PATH I10
J 0
(-2025 275);
DISPLAY 0.872340 (-2025 275);
PAINT AQUA (-2025 275);
DISPLAY INVISIBLE (-2025 275);
FORCEPROP 1 LAST HDL_POWER GND
J 1
(-2075 200);
DISPLAY 0.702128 (-2075 200);
PAINT GREEN (-2075 200);
DISPLAY INVISIBLE (-2075 200);
FORCEPROP 2 LAST CDS_LIB logical_power
J 0
(-2100 275);
DISPLAY INVISIBLE (-2100 275);
FORCEADD Q_CAP..1
(-2100 575);
FORCEPROP 1 LAST MATERIAL X7R
J 0
(-2050 525);
DISPLAY 0.510638 (-2050 525);
PAINT SKYBLUE (-2050 525);
FORCEPROP 1 LAST VOLTAGE 25V
J 0
(-2050 575);
DISPLAY 0.510638 (-2050 575);
PAINT SKYBLUE (-2050 575);
FORCEPROP 1 LAST VALUE 0.1UF
J 0
(-2050 600);
DISPLAY 0.510638 (-2050 600);
PAINT SKYBLUE (-2050 600);
FORCEPROP 1 LAST PACK_TYPE 0402
J 0
(-2050 500);
DISPLAY 0.510638 (-2050 500);
PAINT SKYBLUE (-2050 500);
FORCEPROP 1 LAST TOLERANCE 10%
J 0
(-2050 550);
DISPLAY 0.510638 (-2050 550);
PAINT SKYBLUE (-2050 550);
FORCEPROP 1 LAST PATH I11
J 0
(-2050 725);
DISPLAY 0.978723 (-2050 725);
PAINT WHITE (-2050 725);
DISPLAY INVISIBLE (-2050 725);
FORCEPROP 1 LAST PART_NUMBER CH4104K1B00
R 1
J 0
(-2150 475);
DISPLAY 0.510638 (-2150 475);
PAINT WHITE (-2150 475);
DISPLAY INVISIBLE (-2150 475);
FORCEPROP 2 LAST CDS_LIB pure_quanta
J 0
(-2100 575);
DISPLAY INVISIBLE (-2100 575);
FORCEPROP 1 LAST LOCATION C202
J 0
(-2050 625);
DISPLAY 0.702128 (-2050 625);
PAINT YELLOW (-2050 625);
FORCEPROP 1 LASTPIN (-2100 675) $PN 1
J 0
(-2090 655);
DISPLAY 0.808511 (-2090 655);
PAINT WHITE (-2090 655);
FORCEPROP 1 LASTPIN (-2100 475) $PN 2
J 0
(-2090 455);
DISPLAY 0.808511 (-2090 455);
PAINT WHITE (-2090 455);
FORCEPROP 2 LAST $SEC 1
J 0
(-2050 775);
DISPLAY 0.680851 (-2050 775);
PAINT MONO (-2050 775);
DISPLAY INVISIBLE (-2050 775);
FORCEPROP 2 LAST CDS_SEC 1
J 0
(-2050 775);
DISPLAY 0.680851 (-2050 775);
DISPLAY INVISIBLE (-2050 775);
FORCEADD Q_CAP..1
(-1875 575);
FORCEPROP 1 LAST MATERIAL X7R
J 0
(-1825 525);
DISPLAY 0.510638 (-1825 525);
PAINT SKYBLUE (-1825 525);
FORCEPROP 1 LAST TOLERANCE 10%
J 0
(-1825 550);
DISPLAY 0.510638 (-1825 550);
PAINT SKYBLUE (-1825 550);
FORCEPROP 1 LAST VOLTAGE 25V
J 0
(-1825 575);
DISPLAY 0.510638 (-1825 575);
PAINT SKYBLUE (-1825 575);
FORCEPROP 1 LAST PACK_TYPE 0402
J 0
(-1825 500);
DISPLAY 0.510638 (-1825 500);
PAINT SKYBLUE (-1825 500);
FORCEPROP 1 LAST VALUE 0.1UF
J 0
(-1825 600);
DISPLAY 0.510638 (-1825 600);
PAINT SKYBLUE (-1825 600);
FORCEPROP 1 LAST PATH I12
J 0
(-1825 725);
DISPLAY 0.978723 (-1825 725);
PAINT WHITE (-1825 725);
DISPLAY INVISIBLE (-1825 725);
FORCEPROP 1 LAST PART_NUMBER CH4104K1B00
R 1
J 0
(-1925 475);
DISPLAY 0.510638 (-1925 475);
PAINT WHITE (-1925 475);
DISPLAY INVISIBLE (-1925 475);
FORCEPROP 2 LAST CDS_LIB pure_quanta
J 0
(-1875 575);
DISPLAY INVISIBLE (-1875 575);
FORCEPROP 1 LAST LOCATION C203
J 0
(-1825 625);
DISPLAY 0.702128 (-1825 625);
PAINT YELLOW (-1825 625);
FORCEPROP 1 LASTPIN (-1875 675) $PN 1
J 0
(-1865 655);
DISPLAY 0.808511 (-1865 655);
PAINT WHITE (-1865 655);
FORCEPROP 1 LASTPIN (-1875 475) $PN 2
J 0
(-1865 455);
DISPLAY 0.808511 (-1865 455);
PAINT WHITE (-1865 455);
FORCEPROP 2 LAST $SEC 1
J 0
(-1825 775);
DISPLAY 0.680851 (-1825 775);
PAINT MONO (-1825 775);
DISPLAY INVISIBLE (-1825 775);
FORCEPROP 2 LAST CDS_SEC 1
J 0
(-1825 775);
DISPLAY 0.680851 (-1825 775);
DISPLAY INVISIBLE (-1825 775);
FORCEADD UNIVERSAL_POWER..1
(-2100 900);
FORCEPROP 3 LASTPIN (-2100 850) SIG_NAME P5V_AUX\g
J 0
(-2090 860);
DISPLAY 0.659574 (-2090 860);
PAINT MONO (-2090 860);
DISPLAY INVISIBLE (-2090 860);
FORCEPROP 1 LAST HDL_POWER P5V_AUX
J 1
(-2100 950);
DISPLAY 0.702128 (-2100 950);
PAINT RED (-2100 950);
FORCEPROP 1 LAST PATH I13
J 0
(-2050 925);
DISPLAY 0.872340 (-2050 925);
PAINT AQUA (-2050 925);
DISPLAY INVISIBLE (-2050 925);
FORCEPROP 2 LAST CDS_LIB logical_power
J 0
(-2100 900);
DISPLAY INVISIBLE (-2100 900);
FORCEADD OFFPAGE..1
(-1950 1400);
FORCEPROP 2 LAST $XR0 15 
J 0
(-2201 1400);
DISPLAY 0.638298 (-2201 1400);
PAINT MONO (-2201 1400);
FORCEPROP 2 LAST PATH I14
J 0
(-2150 1450);
DISPLAY 1.021277 (-2150 1450);
DISPLAY INVISIBLE (-2150 1450);
FORCEPROP 1 LAST COMMENT_BODY TRUE
J 0
(-1825 1300);
DISPLAY 0.851064 (-1825 1300);
PAINT PEACH (-1825 1300);
DISPLAY INVISIBLE (-1825 1300);
FORCEPROP 1 LAST OFFPAGE TRUE
J 0
(-1625 1275);
DISPLAY 0.851064 (-1625 1275);
PAINT GREEN (-1625 1275);
DISPLAY INVISIBLE (-1625 1275);
FORCEPROP 2 LAST CDS_LIB standard
J 0
(-1950 1400);
DISPLAY 0.978723 (-1950 1400);
DISPLAY INVISIBLE (-1950 1400);
FORCEADD OFFPAGE..1
(5075 -725);
FORCEPROP 2 LAST $XR0 23 
J 0
(4824 -725);
DISPLAY 0.638298 (4824 -725);
PAINT MONO (4824 -725);
FORCEPROP 2 LAST CDS_LIB standard
J 0
(5075 -725);
DISPLAY INVISIBLE (5075 -725);
FORCEPROP 1 LAST OFFPAGE TRUE
J 0
(5400 -850);
DISPLAY 1.574468 (5400 -850);
PAINT GREEN (5400 -850);
DISPLAY INVISIBLE (5400 -850);
FORCEPROP 1 LAST COMMENT_BODY TRUE
J 0
(5200 -825);
DISPLAY 1.574468 (5200 -825);
PAINT PEACH (5200 -825);
DISPLAY INVISIBLE (5200 -825);
FORCEPROP 2 LAST PATH I143
J 0
(5125 -650);
DISPLAY 1.021277 (5125 -650);
DISPLAY INVISIBLE (5125 -650);
FORCEADD OFFPAGE..6
(5075 -675);
FORCEPROP 2 LAST $XR0 23 
J 0
(4826 -675);
DISPLAY 0.638298 (4826 -675);
PAINT MONO (4826 -675);
FORCEPROP 2 LAST CDS_LIB standard
J 0
(5075 -675);
DISPLAY INVISIBLE (5075 -675);
FORCEPROP 1 LAST OFFPAGE TRUE
J 0
(5400 -800);
DISPLAY 0.872340 (5400 -800);
PAINT GREEN (5400 -800);
DISPLAY INVISIBLE (5400 -800);
FORCEPROP 1 LAST COMMENT_BODY TRUE
J 0
(5175 -750);
DISPLAY 0.872340 (5175 -750);
PAINT PEACH (5175 -750);
DISPLAY INVISIBLE (5175 -750);
FORCEPROP 2 LAST PATH I144
J 0
(5125 -600);
DISPLAY 1.021277 (5125 -600);
DISPLAY INVISIBLE (5125 -600);
FORCEADD OFFPAGE..1
(5075 -375);
FORCEPROP 2 LAST $XR0 23 
J 0
(4854 -375);
DISPLAY 0.638298 (4854 -375);
PAINT MONO (4854 -375);
FORCEPROP 2 LAST CDS_LIB standard
J 0
(5075 -375);
DISPLAY INVISIBLE (5075 -375);
FORCEPROP 1 LAST OFFPAGE TRUE
J 0
(5400 -500);
DISPLAY 1.574468 (5400 -500);
PAINT GREEN (5400 -500);
DISPLAY INVISIBLE (5400 -500);
FORCEPROP 1 LAST COMMENT_BODY TRUE
J 0
(5200 -475);
DISPLAY 1.574468 (5200 -475);
PAINT PEACH (5200 -475);
DISPLAY INVISIBLE (5200 -475);
FORCEPROP 2 LAST PATH I145
J 0
(5125 -300);
DISPLAY 1.021277 (5125 -300);
DISPLAY INVISIBLE (5125 -300);
FORCEADD OFFPAGE..1
(5075 -275);
FORCEPROP 2 LAST $XR0 23 
J 0
(4854 -275);
DISPLAY 0.638298 (4854 -275);
PAINT MONO (4854 -275);
FORCEPROP 2 LAST CDS_LIB standard
J 0
(5075 -275);
DISPLAY INVISIBLE (5075 -275);
FORCEPROP 1 LAST OFFPAGE TRUE
J 0
(5400 -400);
DISPLAY 1.574468 (5400 -400);
PAINT GREEN (5400 -400);
DISPLAY INVISIBLE (5400 -400);
FORCEPROP 1 LAST COMMENT_BODY TRUE
J 0
(5200 -375);
DISPLAY 1.574468 (5200 -375);
PAINT PEACH (5200 -375);
DISPLAY INVISIBLE (5200 -375);
FORCEPROP 2 LAST PATH I146
J 0
(5125 -200);
DISPLAY 1.021277 (5125 -200);
DISPLAY INVISIBLE (5125 -200);
FORCEADD OFFPAGE..1
(5075 -175);
FORCEPROP 2 LAST $XR0 23 
J 0
(4854 -175);
DISPLAY 0.638298 (4854 -175);
PAINT MONO (4854 -175);
FORCEPROP 1 LAST COMMENT_BODY TRUE
J 0
(5200 -275);
DISPLAY 1.574468 (5200 -275);
PAINT PEACH (5200 -275);
DISPLAY INVISIBLE (5200 -275);
FORCEPROP 1 LAST OFFPAGE TRUE
J 0
(5400 -300);
DISPLAY 1.574468 (5400 -300);
PAINT GREEN (5400 -300);
DISPLAY INVISIBLE (5400 -300);
FORCEPROP 2 LAST CDS_LIB standard
J 0
(5075 -175);
DISPLAY INVISIBLE (5075 -175);
FORCEPROP 2 LAST PATH I147
J 0
(5125 -100);
DISPLAY 1.021277 (5125 -100);
DISPLAY INVISIBLE (5125 -100);
FORCEADD OFFPAGE..1
(5075 -575);
FORCEPROP 2 LAST $XR0 23 
J 0
(4854 -575);
DISPLAY 0.638298 (4854 -575);
PAINT MONO (4854 -575);
FORCEPROP 2 LAST CDS_LIB standard
J 0
(5075 -575);
DISPLAY INVISIBLE (5075 -575);
FORCEPROP 1 LAST OFFPAGE TRUE
J 0
(5400 -700);
DISPLAY 1.574468 (5400 -700);
PAINT GREEN (5400 -700);
DISPLAY INVISIBLE (5400 -700);
FORCEPROP 1 LAST COMMENT_BODY TRUE
J 0
(5200 -675);
DISPLAY 1.574468 (5200 -675);
PAINT PEACH (5200 -675);
DISPLAY INVISIBLE (5200 -675);
FORCEPROP 2 LAST PATH I148
J 0
(5125 -500);
DISPLAY 1.021277 (5125 -500);
DISPLAY INVISIBLE (5125 -500);
FORCEADD OFFPAGE..1
(5075 -475);
FORCEPROP 2 LAST $XR0 23 
J 0
(4854 -475);
DISPLAY 0.638298 (4854 -475);
PAINT MONO (4854 -475);
FORCEPROP 2 LAST CDS_LIB standard
J 0
(5075 -475);
DISPLAY INVISIBLE (5075 -475);
FORCEPROP 1 LAST OFFPAGE TRUE
J 0
(5400 -600);
DISPLAY 1.574468 (5400 -600);
PAINT GREEN (5400 -600);
DISPLAY INVISIBLE (5400 -600);
FORCEPROP 1 LAST COMMENT_BODY TRUE
J 0
(5200 -575);
DISPLAY 1.574468 (5200 -575);
PAINT PEACH (5200 -575);
DISPLAY INVISIBLE (5200 -575);
FORCEPROP 2 LAST PATH I149
J 0
(5125 -400);
DISPLAY 1.021277 (5125 -400);
DISPLAY INVISIBLE (5125 -400);
FORCEADD OFFPAGE..1
(-1950 1700);
FORCEPROP 2 LAST $XR0 15 
J 0
(-2201 1700);
DISPLAY 0.638298 (-2201 1700);
PAINT MONO (-2201 1700);
FORCEPROP 2 LAST PATH I15
J 0
(-2150 1750);
DISPLAY 1.021277 (-2150 1750);
DISPLAY INVISIBLE (-2150 1750);
FORCEPROP 1 LAST COMMENT_BODY TRUE
J 0
(-1825 1600);
DISPLAY 0.851064 (-1825 1600);
PAINT PEACH (-1825 1600);
DISPLAY INVISIBLE (-1825 1600);
FORCEPROP 1 LAST OFFPAGE TRUE
J 0
(-1625 1575);
DISPLAY 0.851064 (-1625 1575);
PAINT GREEN (-1625 1575);
DISPLAY INVISIBLE (-1625 1575);
FORCEPROP 2 LAST CDS_LIB standard
J 0
(-1950 1700);
DISPLAY 0.978723 (-1950 1700);
DISPLAY INVISIBLE (-1950 1700);
FORCEADD UNIVERSAL_GND..1
(5950 -1025);
FORCEPROP 3 LASTPIN (5950 -975) SIG_NAME GND\g
J 0
(5960 -965);
DISPLAY 0.659574 (5960 -965);
PAINT MONO (5960 -965);
DISPLAY INVISIBLE (5960 -965);
FORCEPROP 1 LAST HDL_POWER GND
J 1
(5975 -1100);
DISPLAY 0.702128 (5975 -1100);
PAINT GREEN (5975 -1100);
DISPLAY INVISIBLE (5975 -1100);
FORCEPROP 1 LAST PATH I150
J 0
(6025 -1025);
DISPLAY 0.872340 (6025 -1025);
PAINT AQUA (6025 -1025);
DISPLAY INVISIBLE (6025 -1025);
FORCEPROP 2 LAST CDS_LIB logical_power
J 0
(5950 -1025);
DISPLAY INVISIBLE (5950 -1025);
FORCEADD Q_FUSE..1
(4400 -775);
FORCEPROP 2 LAST PACK_TYPE SMLF
J 0
(4350 -600);
DISPLAY 0.680851 (4350 -600);
FORCEPROP 2 LAST VALUE 1.1A/8V
J 0
(4350 -550);
DISPLAY 0.680851 (4350 -550);
FORCEPROP 1 LAST MATERIAL EMPTY
J 0
(4350 -740);
DISPLAY 0.723404 (4350 -740);
PAINT RED (4350 -740);
FORCEPROP 1 LAST PART_NUMBER DK110TPU003
J 0
(4350 -690);
DISPLAY 0.723404 (4350 -690);
PAINT GREEN (4350 -690);
FORCEPROP 1 LAST NEEDS_NO_SIZE TRUE
J 0
(4400 -775);
DISPLAY 0.468085 (4400 -775);
PAINT GREEN (4400 -775);
DISPLAY INVISIBLE (4400 -775);
FORCEPROP 2 LAST CDS_LIB pure_quanta
J 0
(4400 -775);
DISPLAY INVISIBLE (4400 -775);
FORCEPROP 2 LAST SEC_TYPE SMLF
J 0
(4350 -500);
DISPLAY 0.680851 (4350 -500);
DISPLAY INVISIBLE (4350 -500);
FORCEPROP 1 LAST PATH I153
J 0
(4425 -720);
DISPLAY 0.723404 (4425 -720);
PAINT GREEN (4425 -720);
DISPLAY INVISIBLE (4425 -720);
FORCEPROP 1 LAST LOCATION FS1
J 0
(4350 -645);
DISPLAY 0.723404 (4350 -645);
PAINT GREEN (4350 -645);
FORCEPROP 2 LASTPIN (4300 -775) $PN 1
J 2
(4290 -765);
DISPLAY 0.680851 (4290 -765);
PAINT MONO (4290 -765);
FORCEPROP 2 LASTPIN (4500 -775) $PN 2
J 0
(4510 -765);
DISPLAY 0.680851 (4510 -765);
PAINT MONO (4510 -765);
FORCEPROP 2 LAST SEC 1
J 0
(4350 -500);
DISPLAY 0.680851 (4350 -500);
PAINT MONO (4350 -500);
DISPLAY INVISIBLE (4350 -500);
FORCEADD UNIVERSAL_POWER..1
(3050 -475);
FORCEPROP 3 LASTPIN (3050 -525) SIG_NAME P5V_AUX\g
J 0
(3060 -515);
DISPLAY 0.659574 (3060 -515);
PAINT MONO (3060 -515);
DISPLAY INVISIBLE (3060 -515);
FORCEPROP 1 LAST HDL_POWER P5V_AUX
J 1
(3050 -425);
DISPLAY 0.702128 (3050 -425);
PAINT GREEN (3050 -425);
FORCEPROP 2 LAST CDS_LIB logical_power
J 0
(3050 -475);
DISPLAY INVISIBLE (3050 -475);
FORCEPROP 1 LAST PATH I154
J 0
(3100 -450);
DISPLAY 0.872340 (3100 -450);
PAINT AQUA (3100 -450);
DISPLAY INVISIBLE (3100 -450);
FORCEADD DT1240E04LP7..1
(3300 4000);
FORCEPROP 1 LAST PART_NUMBER BC001240Z01
J 0
(3055 4534);
DISPLAY 0.723404 (3055 4534);
PAINT GREEN (3055 4534);
FORCEPROP 2 LAST PART_TYPE SMLF
J 0
(3075 4775);
DISPLAY 0.680851 (3075 4775);
FORCEPROP 2 LAST VALUE DT1240E-04LP-7
J 0
(3075 4725);
DISPLAY 0.680851 (3075 4725);
FORCEPROP 1 LAST MATERIAL IC
J 0
(3055 4407);
DISPLAY 0.723404 (3055 4407);
PAINT GREEN (3055 4407);
FORCEPROP 1 LAST CDS_LMAN_SYM_OUTLINE -250,400,250,-400
J 0
(3300 4000);
DISPLAY 0.468085 (3300 4000);
PAINT GREEN (3300 4000);
DISPLAY INVISIBLE (3300 4000);
FORCEPROP 1 LAST NEEDS_NO_SIZE TRUE
J 0
(3300 4000);
DISPLAY 0.723404 (3300 4000);
PAINT GREEN (3300 4000);
DISPLAY INVISIBLE (3300 4000);
FORCEPROP 1 LAST PATH I155
J 0
(3300 4000);
DISPLAY 0.723404 (3300 4000);
PAINT GREEN (3300 4000);
DISPLAY INVISIBLE (3300 4000);
FORCEPROP 2 LAST CDS_LIB pure_quanta
J 0
(3300 4000);
DISPLAY INVISIBLE (3300 4000);
FORCEPROP 1 LAST LOCATION U35
J 0
(3055 4681);
DISPLAY 0.723404 (3055 4681);
PAINT GREEN (3055 4681);
FORCEPROP 0 LASTPIN (2900 4300) $PN 1
J 2
(2890 4310);
DISPLAY 0.680851 (2890 4310);
PAINT MONO (2890 4310);
FORCEPROP 0 LASTPIN (2900 4150) $PN 2
J 2
(2890 4160);
DISPLAY 0.680851 (2890 4160);
PAINT MONO (2890 4160);
FORCEPROP 0 LASTPIN (2900 4000) $PN 4
J 2
(2890 4010);
DISPLAY 0.680851 (2890 4010);
PAINT MONO (2890 4010);
FORCEPROP 0 LASTPIN (2900 3850) $PN 5
J 2
(2890 3860);
DISPLAY 0.680851 (2890 3860);
PAINT MONO (2890 3860);
FORCEPROP 0 LASTPIN (3700 3800) $PN 6
J 0
(3710 3810);
DISPLAY 0.680851 (3710 3810);
PAINT MONO (3710 3810);
FORCEPROP 0 LASTPIN (3700 3750) $PN 7
J 0
(3710 3760);
DISPLAY 0.680851 (3710 3760);
PAINT MONO (3710 3760);
FORCEPROP 0 LASTPIN (3700 3700) $PN 9
J 0
(3710 3710);
DISPLAY 0.680851 (3710 3710);
PAINT MONO (3710 3710);
FORCEPROP 0 LASTPIN (3700 3650) $PN 10
J 0
(3710 3660);
DISPLAY 0.680851 (3710 3660);
PAINT MONO (3710 3660);
FORCEPROP 0 LASTPIN (3700 4300) $PN 3
J 0
(3710 4310);
DISPLAY 0.680851 (3710 4310);
PAINT MONO (3710 4310);
FORCEPROP 0 LASTPIN (3700 4150) $PN 8
J 0
(3710 4160);
DISPLAY 0.680851 (3710 4160);
PAINT MONO (3710 4160);
FORCEPROP 0 LAST $SEC 1
J 0
(3075 4825);
DISPLAY 0.680851 (3075 4825);
PAINT MONO (3075 4825);
DISPLAY INVISIBLE (3075 4825);
FORCEPROP 0 LAST CDS_SEC 1
J 0
(3075 4825);
DISPLAY 0.680851 (3075 4825);
DISPLAY INVISIBLE (3075 4825);
FORCEADD DT1240E04LP7..1
(1550 4000);
FORCEPROP 1 LAST PART_NUMBER BC001240Z01
J 0
(1305 4534);
DISPLAY 0.723404 (1305 4534);
PAINT GREEN (1305 4534);
FORCEPROP 2 LAST VALUE DT1240E-04LP-7
J 0
(1325 4725);
DISPLAY 0.680851 (1325 4725);
FORCEPROP 1 LAST MATERIAL IC
J 0
(1305 4407);
DISPLAY 0.723404 (1305 4407);
PAINT GREEN (1305 4407);
FORCEPROP 2 LAST PART_TYPE SMLF
J 0
(1325 4775);
DISPLAY 0.680851 (1325 4775);
FORCEPROP 1 LAST NEEDS_NO_SIZE TRUE
J 0
(1550 4000);
DISPLAY 0.723404 (1550 4000);
PAINT GREEN (1550 4000);
DISPLAY INVISIBLE (1550 4000);
FORCEPROP 1 LAST CDS_LMAN_SYM_OUTLINE -250,400,250,-400
J 0
(1550 4000);
DISPLAY 0.468085 (1550 4000);
PAINT GREEN (1550 4000);
DISPLAY INVISIBLE (1550 4000);
FORCEPROP 1 LAST PATH I156
J 0
(1550 4000);
DISPLAY 0.723404 (1550 4000);
PAINT GREEN (1550 4000);
DISPLAY INVISIBLE (1550 4000);
FORCEPROP 2 LAST CDS_LIB pure_quanta
J 0
(1550 4000);
DISPLAY INVISIBLE (1550 4000);
FORCEPROP 1 LAST LOCATION U34
J 0
(1305 4681);
DISPLAY 0.723404 (1305 4681);
PAINT GREEN (1305 4681);
FORCEPROP 0 LASTPIN (1150 4300) $PN 1
J 2
(1140 4310);
DISPLAY 0.680851 (1140 4310);
PAINT MONO (1140 4310);
FORCEPROP 0 LASTPIN (1150 4150) $PN 2
J 2
(1140 4160);
DISPLAY 0.680851 (1140 4160);
PAINT MONO (1140 4160);
FORCEPROP 0 LASTPIN (1150 4000) $PN 4
J 2
(1140 4010);
DISPLAY 0.680851 (1140 4010);
PAINT MONO (1140 4010);
FORCEPROP 0 LASTPIN (1150 3850) $PN 5
J 2
(1140 3860);
DISPLAY 0.680851 (1140 3860);
PAINT MONO (1140 3860);
FORCEPROP 0 LASTPIN (1950 3800) $PN 6
J 0
(1960 3810);
DISPLAY 0.680851 (1960 3810);
PAINT MONO (1960 3810);
FORCEPROP 0 LASTPIN (1950 3750) $PN 7
J 0
(1960 3760);
DISPLAY 0.680851 (1960 3760);
PAINT MONO (1960 3760);
FORCEPROP 0 LASTPIN (1950 3700) $PN 9
J 0
(1960 3710);
DISPLAY 0.680851 (1960 3710);
PAINT MONO (1960 3710);
FORCEPROP 0 LASTPIN (1950 3650) $PN 10
J 0
(1960 3660);
DISPLAY 0.680851 (1960 3660);
PAINT MONO (1960 3660);
FORCEPROP 0 LASTPIN (1950 4300) $PN 3
J 0
(1960 4310);
DISPLAY 0.680851 (1960 4310);
PAINT MONO (1960 4310);
FORCEPROP 0 LASTPIN (1950 4150) $PN 8
J 0
(1960 4160);
DISPLAY 0.680851 (1960 4160);
PAINT MONO (1960 4160);
FORCEPROP 0 LAST $SEC 1
J 0
(1325 4825);
DISPLAY 0.680851 (1325 4825);
PAINT MONO (1325 4825);
DISPLAY INVISIBLE (1325 4825);
FORCEPROP 0 LAST CDS_SEC 1
J 0
(1325 4825);
DISPLAY 0.680851 (1325 4825);
DISPLAY INVISIBLE (1325 4825);
FORCEADD UNIVERSAL_GND..1
(2050 4000);
FORCEPROP 3 LASTPIN (2050 4050) SIG_NAME GND\g
J 0
(2060 4060);
DISPLAY 0.659574 (2060 4060);
PAINT MONO (2060 4060);
DISPLAY INVISIBLE (2060 4060);
FORCEPROP 2 LAST CDS_LIB logical_power
J 0
(2050 4000);
DISPLAY INVISIBLE (2050 4000);
FORCEPROP 1 LAST PATH I157
J 0
(2125 4000);
DISPLAY 0.872340 (2125 4000);
PAINT AQUA (2125 4000);
DISPLAY INVISIBLE (2125 4000);
FORCEPROP 1 LAST HDL_POWER GND
J 1
(2075 3925);
DISPLAY 0.702128 (2075 3925);
PAINT GREEN (2075 3925);
DISPLAY INVISIBLE (2075 3925);
FORCEADD UNIVERSAL_GND..1
(3800 4000);
FORCEPROP 3 LASTPIN (3800 4050) SIG_NAME GND\g
J 0
(3810 4060);
DISPLAY 0.659574 (3810 4060);
PAINT MONO (3810 4060);
DISPLAY INVISIBLE (3810 4060);
FORCEPROP 1 LAST HDL_POWER GND
J 1
(3825 3925);
DISPLAY 0.702128 (3825 3925);
PAINT GREEN (3825 3925);
DISPLAY INVISIBLE (3825 3925);
FORCEPROP 1 LAST PATH I158
J 0
(3875 4000);
DISPLAY 0.872340 (3875 4000);
PAINT AQUA (3875 4000);
DISPLAY INVISIBLE (3875 4000);
FORCEPROP 2 LAST CDS_LIB logical_power
J 0
(3800 4000);
DISPLAY INVISIBLE (3800 4000);
FORCEADD OFFPAGE..1
(-1950 2000);
FORCEPROP 2 LAST $XR0 15 
J 0
(-2201 2000);
DISPLAY 0.638298 (-2201 2000);
PAINT MONO (-2201 2000);
FORCEPROP 2 LAST PATH I16
J 0
(-2150 2050);
DISPLAY 1.021277 (-2150 2050);
DISPLAY INVISIBLE (-2150 2050);
FORCEPROP 1 LAST COMMENT_BODY TRUE
J 0
(-1825 1900);
DISPLAY 0.851064 (-1825 1900);
PAINT PEACH (-1825 1900);
DISPLAY INVISIBLE (-1825 1900);
FORCEPROP 1 LAST OFFPAGE TRUE
J 0
(-1625 1875);
DISPLAY 0.851064 (-1625 1875);
PAINT GREEN (-1625 1875);
DISPLAY INVISIBLE (-1625 1875);
FORCEPROP 2 LAST CDS_LIB standard
J 0
(-1950 2000);
DISPLAY 0.978723 (-1950 2000);
DISPLAY INVISIBLE (-1950 2000);
FORCEADD SCHOTTKY_12..1
(3425 -775);
FORCEPROP 2 LAST VALUE SBA130Q
J 0
(3350 -550);
DISPLAY 0.680851 (3350 -550);
FORCEPROP 2 LAST PART_TYPE SMLF
J 0
(3350 -500);
DISPLAY 0.680851 (3350 -500);
FORCEPROP 1 LAST PART_NUMBER BCSBA130Z00
J 0
(3350 -650);
DISPLAY 0.723404 (3350 -650);
PAINT GREEN (3350 -650);
FORCEPROP 1 LAST MATERIAL EMPTY
J 0
(3350 -700);
DISPLAY 0.723404 (3350 -700);
PAINT RED (3350 -700);
FORCEPROP 2 LAST CDS_LIB pure_quanta
J 0
(3425 -775);
DISPLAY INVISIBLE (3425 -775);
FORCEPROP 1 LAST PATH I161
J 0
(3425 -775);
DISPLAY 0.723404 (3425 -775);
PAINT GREEN (3425 -775);
DISPLAY INVISIBLE (3425 -775);
FORCEPROP 1 LAST NEEDS_NO_SIZE TRUE
J 0
(3500 -825);
DISPLAY 0.468085 (3500 -825);
PAINT GREEN (3500 -825);
DISPLAY INVISIBLE (3500 -825);
FORCEPROP 1 LAST CDS_LMAN_SYM_OUTLINE -75,50,75,-50
J 0
(3425 -775);
DISPLAY 0.468085 (3425 -775);
PAINT GREEN (3425 -775);
DISPLAY INVISIBLE (3425 -775);
FORCEPROP 1 LAST LOCATION D16
J 0
(3350 -600);
DISPLAY 0.723404 (3350 -600);
PAINT GREEN (3350 -600);
FORCEPROP 0 LASTPIN (3300 -775) $PN 1
J 2
(3290 -765);
DISPLAY 0.680851 (3290 -765);
PAINT MONO (3290 -765);
FORCEPROP 0 LASTPIN (3550 -775) $PN 2
J 0
(3560 -765);
DISPLAY 0.680851 (3560 -765);
PAINT MONO (3560 -765);
FORCEPROP 0 LAST $SEC 1
J 0
(3350 -450);
DISPLAY 0.680851 (3350 -450);
PAINT MONO (3350 -450);
DISPLAY INVISIBLE (3350 -450);
FORCEPROP 0 LAST CDS_SEC 1
J 0
(3350 -450);
DISPLAY 0.680851 (3350 -450);
DISPLAY INVISIBLE (3350 -450);
FORCEADD SCONN13_502280130CV01..1
R 2
(6250 -550);
FORCEPROP 2 LAST VALUE SCONN13_50228-0130C-V01
J 2
(6300 100);
DISPLAY 0.680851 (6300 100);
FORCEPROP 2 LAST PART_TYPE SMLF
J 2
(6300 150);
DISPLAY 0.680851 (6300 150);
FORCEPROP 1 LAST MATERIAL IO
J 2
(6323 -121);
DISPLAY 0.723404 (6323 -121);
PAINT GREEN (6323 -121);
FORCEPROP 1 LAST PART_NUMBER DFHD13MS080
J 2
(6323 -42);
DISPLAY 0.723404 (6323 -42);
PAINT GREEN (6323 -42);
FORCEPROP 2 LAST CDS_LIB pure_quanta
J 2
(6250 -550);
DISPLAY INVISIBLE (6250 -550);
FORCEPROP 1 LAST PATH I165
J 2
(6250 -550);
DISPLAY 0.723404 (6250 -550);
PAINT GREEN (6250 -550);
DISPLAY INVISIBLE (6250 -550);
FORCEPROP 1 LAST NEEDS_NO_SIZE TRUE
J 2
(6250 -550);
DISPLAY 0.723404 (6250 -550);
PAINT GREEN (6250 -550);
DISPLAY INVISIBLE (6250 -550);
FORCEPROP 1 LAST CDS_LMAN_SYM_OUTLINE -75,425,75,-425
J 2
(6250 -550);
DISPLAY 0.468085 (6250 -550);
PAINT GREEN (6250 -550);
DISPLAY INVISIBLE (6250 -550);
FORCEPROP 1 LAST LOCATION J8
J 2
(6323 45);
DISPLAY 0.723404 (6323 45);
PAINT GREEN (6323 45);
FORCEPROP 0 LASTPIN (6025 -175) $PN 1
J 2
(6015 -165);
DISPLAY 0.680851 (6015 -165);
PAINT MONO (6015 -165);
FORCEPROP 0 LASTPIN (6025 -225) $PN 2
J 2
(6015 -215);
DISPLAY 0.680851 (6015 -215);
PAINT MONO (6015 -215);
FORCEPROP 0 LASTPIN (6025 -275) $PN 3
J 2
(6015 -265);
DISPLAY 0.680851 (6015 -265);
PAINT MONO (6015 -265);
FORCEPROP 0 LASTPIN (6025 -325) $PN 4
J 2
(6015 -315);
DISPLAY 0.680851 (6015 -315);
PAINT MONO (6015 -315);
FORCEPROP 0 LASTPIN (6025 -375) $PN 5
J 2
(6015 -365);
DISPLAY 0.680851 (6015 -365);
PAINT MONO (6015 -365);
FORCEPROP 0 LASTPIN (6025 -425) $PN 6
J 2
(6015 -415);
DISPLAY 0.680851 (6015 -415);
PAINT MONO (6015 -415);
FORCEPROP 0 LASTPIN (6025 -475) $PN 7
J 2
(6015 -465);
DISPLAY 0.680851 (6015 -465);
PAINT MONO (6015 -465);
FORCEPROP 0 LASTPIN (6025 -525) $PN 8
J 2
(6015 -515);
DISPLAY 0.680851 (6015 -515);
PAINT MONO (6015 -515);
FORCEPROP 0 LASTPIN (6025 -575) $PN 9
J 2
(6015 -565);
DISPLAY 0.680851 (6015 -565);
PAINT MONO (6015 -565);
FORCEPROP 0 LASTPIN (6025 -625) $PN 10
J 2
(6015 -615);
DISPLAY 0.680851 (6015 -615);
PAINT MONO (6015 -615);
FORCEPROP 0 LASTPIN (6025 -675) $PN 11
J 2
(6015 -665);
DISPLAY 0.680851 (6015 -665);
PAINT MONO (6015 -665);
FORCEPROP 0 LASTPIN (6025 -725) $PN 12
J 2
(6015 -715);
DISPLAY 0.680851 (6015 -715);
PAINT MONO (6015 -715);
FORCEPROP 0 LASTPIN (6025 -775) $PN 13
J 2
(6015 -765);
DISPLAY 0.680851 (6015 -765);
PAINT MONO (6015 -765);
FORCEPROP 0 LASTPIN (6025 -875) $PN G1
J 2
(6015 -865);
DISPLAY 0.680851 (6015 -865);
PAINT MONO (6015 -865);
FORCEPROP 0 LASTPIN (6025 -925) $PN G2
J 2
(6015 -915);
DISPLAY 0.680851 (6015 -915);
PAINT MONO (6015 -915);
FORCEPROP 0 LAST $SEC 1
J 0
(6300 200);
DISPLAY 0.680851 (6300 200);
PAINT MONO (6300 200);
DISPLAY INVISIBLE (6300 200);
FORCEPROP 0 LAST CDS_SEC 1
J 0
(6300 200);
DISPLAY 0.680851 (6300 200);
DISPLAY INVISIBLE (6300 200);
FORCEADD Q_INDUCTOR..1
(-75 2025);
FORCEPROP 1 LAST MATERIAL IND
J 0
(-200 2080);
DISPLAY 0.723404 (-200 2080);
PAINT GREEN (-200 2080);
FORCEPROP 2 LAST PACK_TYPE SMLF
J 0
(-200 2225);
DISPLAY 0.680851 (-200 2225);
FORCEPROP 1 LAST PART_NUMBER CX8BB470007
J 0
(-200 2135);
DISPLAY 0.723404 (-200 2135);
PAINT GREEN (-200 2135);
FORCEPROP 2 LAST VALUE BLM18BB470/500MA
J 0
(-200 2275);
DISPLAY 0.680851 (-200 2275);
FORCEPROP 1 LAST NEEDS_NO_SIZE TRUE
J 0
(-75 2025);
DISPLAY 0.468085 (-75 2025);
PAINT GREEN (-75 2025);
DISPLAY INVISIBLE (-75 2025);
FORCEPROP 1 LAST PATH I166
J 0
(0 2080);
DISPLAY 0.723404 (0 2080);
PAINT GREEN (0 2080);
DISPLAY INVISIBLE (0 2080);
FORCEPROP 2 LAST CDS_LIB pure_quanta
J 0
(-75 2025);
DISPLAY INVISIBLE (-75 2025);
FORCEPROP 1 LAST LOCATION L28
J 0
(-200 2185);
DISPLAY 0.723404 (-200 2185);
PAINT GREEN (-200 2185);
FORCEPROP 0 LASTPIN (-175 2000) $PN 1
J 2
(-185 2010);
DISPLAY 0.680851 (-185 2010);
PAINT MONO (-185 2010);
FORCEPROP 0 LASTPIN (25 2000) $PN 2
J 0
(35 2010);
DISPLAY 0.680851 (35 2010);
PAINT MONO (35 2010);
FORCEPROP 0 LAST $SEC 1
J 0
(-200 2325);
DISPLAY 0.680851 (-200 2325);
PAINT MONO (-200 2325);
DISPLAY INVISIBLE (-200 2325);
FORCEPROP 0 LAST CDS_SEC 1
J 0
(-200 2325);
DISPLAY 0.680851 (-200 2325);
DISPLAY INVISIBLE (-200 2325);
FORCEADD Q_INDUCTOR..1
(-75 1725);
FORCEPROP 1 LAST MATERIAL IND
J 0
(-200 1780);
DISPLAY 0.723404 (-200 1780);
PAINT GREEN (-200 1780);
FORCEPROP 1 LAST PART_NUMBER CX8BB470007
J 0
(-200 1835);
DISPLAY 0.723404 (-200 1835);
PAINT GREEN (-200 1835);
FORCEPROP 2 LAST PACK_TYPE SMLF
J 0
(-200 1925);
DISPLAY 0.680851 (-200 1925);
FORCEPROP 2 LAST VALUE BLM18BB470/500MA
J 0
(-200 1975);
DISPLAY 0.680851 (-200 1975);
FORCEPROP 2 LAST CDS_LIB pure_quanta
J 0
(-75 1725);
DISPLAY INVISIBLE (-75 1725);
FORCEPROP 1 LAST PATH I167
J 0
(0 1780);
DISPLAY 0.723404 (0 1780);
PAINT GREEN (0 1780);
DISPLAY INVISIBLE (0 1780);
FORCEPROP 1 LAST NEEDS_NO_SIZE TRUE
J 0
(-75 1725);
DISPLAY 0.468085 (-75 1725);
PAINT GREEN (-75 1725);
DISPLAY INVISIBLE (-75 1725);
FORCEPROP 1 LAST LOCATION L29
J 0
(-200 1885);
DISPLAY 0.723404 (-200 1885);
PAINT GREEN (-200 1885);
FORCEPROP 0 LASTPIN (-175 1700) $PN 1
J 2
(-185 1710);
DISPLAY 0.680851 (-185 1710);
PAINT MONO (-185 1710);
FORCEPROP 0 LASTPIN (25 1700) $PN 2
J 0
(35 1710);
DISPLAY 0.680851 (35 1710);
PAINT MONO (35 1710);
FORCEPROP 0 LAST $SEC 1
J 0
(-200 2025);
DISPLAY 0.680851 (-200 2025);
PAINT MONO (-200 2025);
DISPLAY INVISIBLE (-200 2025);
FORCEPROP 0 LAST CDS_SEC 1
J 0
(-200 2025);
DISPLAY 0.680851 (-200 2025);
DISPLAY INVISIBLE (-200 2025);
FORCEADD Q_INDUCTOR..1
(-75 1425);
FORCEPROP 2 LAST PACK_TYPE SMLF
J 0
(-200 1625);
DISPLAY 0.680851 (-200 1625);
FORCEPROP 1 LAST MATERIAL IND
J 0
(-200 1480);
DISPLAY 0.723404 (-200 1480);
PAINT GREEN (-200 1480);
FORCEPROP 1 LAST PART_NUMBER CX8BB470007
J 0
(-200 1535);
DISPLAY 0.723404 (-200 1535);
PAINT GREEN (-200 1535);
FORCEPROP 2 LAST VALUE BLM18BB470/500MA
J 0
(-200 1675);
DISPLAY 0.680851 (-200 1675);
FORCEPROP 2 LAST CDS_LIB pure_quanta
J 0
(-75 1425);
DISPLAY INVISIBLE (-75 1425);
FORCEPROP 1 LAST PATH I168
J 0
(0 1480);
DISPLAY 0.723404 (0 1480);
PAINT GREEN (0 1480);
DISPLAY INVISIBLE (0 1480);
FORCEPROP 1 LAST NEEDS_NO_SIZE TRUE
J 0
(-75 1425);
DISPLAY 0.468085 (-75 1425);
PAINT GREEN (-75 1425);
DISPLAY INVISIBLE (-75 1425);
FORCEPROP 1 LAST LOCATION L30
J 0
(-200 1585);
DISPLAY 0.723404 (-200 1585);
PAINT GREEN (-200 1585);
FORCEPROP 0 LASTPIN (-175 1400) $PN 1
J 2
(-185 1410);
DISPLAY 0.680851 (-185 1410);
PAINT MONO (-185 1410);
FORCEPROP 0 LASTPIN (25 1400) $PN 2
J 0
(35 1410);
DISPLAY 0.680851 (35 1410);
PAINT MONO (35 1410);
FORCEPROP 0 LAST $SEC 1
J 0
(-200 1725);
DISPLAY 0.680851 (-200 1725);
PAINT MONO (-200 1725);
DISPLAY INVISIBLE (-200 1725);
FORCEPROP 0 LAST CDS_SEC 1
J 0
(-200 1725);
DISPLAY 0.680851 (-200 1725);
DISPLAY INVISIBLE (-200 1725);
FORCEADD Q_CAP..1
(175 1100);
FORCEPROP 1 LAST VOLTAGE 50V
J 0
(225 1100);
DISPLAY 0.638298 (225 1100);
FORCEPROP 1 LAST TOLERANCE 5%
J 0
(225 1050);
DISPLAY 0.638298 (225 1050);
FORCEPROP 1 LAST MATERIAL NPO
J 0
(225 1000);
DISPLAY 0.638298 (225 1000);
FORCEPROP 1 LAST PACK_TYPE 0402
J 0
(225 900);
DISPLAY 0.638298 (225 900);
FORCEPROP 1 LAST VALUE 22PF
J 0
(225 1150);
DISPLAY 0.638298 (225 1150);
FORCEPROP 1 LAST PART_NUMBER TMP_QCH02206JB08
J 0
(225 950);
DISPLAY 0.638298 (225 950);
FORCEPROP 2 LAST CDS_LIB pure_quanta
J 0
(175 1100);
DISPLAY INVISIBLE (175 1100);
FORCEPROP 1 LAST PATH I169
J 0
(225 1250);
DISPLAY 0.978723 (225 1250);
PAINT WHITE (225 1250);
DISPLAY INVISIBLE (225 1250);
FORCEPROP 1 LAST LOCATION C208
J 0
(225 1200);
DISPLAY 0.638298 (225 1200);
FORCEPROP 1 LASTPIN (175 1200) $PN 1
J 0
(185 1180);
DISPLAY 0.787234 (185 1180);
PAINT MONO (185 1180);
FORCEPROP 1 LASTPIN (175 1000) $PN 2
J 0
(185 980);
DISPLAY 0.787234 (185 980);
PAINT MONO (185 980);
FORCEPROP 0 LAST $SEC 1
J 0
(225 1250);
DISPLAY 0.680851 (225 1250);
PAINT MONO (225 1250);
DISPLAY INVISIBLE (225 1250);
FORCEPROP 0 LAST CDS_SEC 1
J 0
(225 1250);
DISPLAY 0.680851 (225 1250);
DISPLAY INVISIBLE (225 1250);
FORCEADD OFFPAGE..1
(-1950 2325);
FORCEPROP 2 LAST $XR0 15 
J 0
(-2201 2325);
DISPLAY 0.638298 (-2201 2325);
PAINT MONO (-2201 2325);
FORCEPROP 2 LAST PATH I17
J 0
(-2150 2375);
DISPLAY 1.021277 (-2150 2375);
DISPLAY INVISIBLE (-2150 2375);
FORCEPROP 1 LAST COMMENT_BODY TRUE
J 0
(-1825 2225);
DISPLAY 0.851064 (-1825 2225);
PAINT PEACH (-1825 2225);
DISPLAY INVISIBLE (-1825 2225);
FORCEPROP 1 LAST OFFPAGE TRUE
J 0
(-1625 2200);
DISPLAY 0.851064 (-1625 2200);
PAINT GREEN (-1625 2200);
DISPLAY INVISIBLE (-1625 2200);
FORCEPROP 2 LAST CDS_LIB standard
J 0
(-1950 2325);
DISPLAY 0.978723 (-1950 2325);
DISPLAY INVISIBLE (-1950 2325);
FORCEADD Q_CAP..1
(975 1100);
FORCEPROP 1 LAST VOLTAGE 50V
J 0
(1025 1100);
DISPLAY 0.638298 (1025 1100);
FORCEPROP 1 LAST VALUE 22PF
J 0
(1025 1150);
DISPLAY 0.638298 (1025 1150);
FORCEPROP 1 LAST TOLERANCE 5%
J 0
(1025 1050);
DISPLAY 0.638298 (1025 1050);
FORCEPROP 1 LAST MATERIAL NPO
J 0
(1025 1000);
DISPLAY 0.638298 (1025 1000);
FORCEPROP 1 LAST PART_NUMBER TMP_QCH02206JB08
J 0
(1025 950);
DISPLAY 0.638298 (1025 950);
FORCEPROP 1 LAST PACK_TYPE 0402
J 0
(1025 900);
DISPLAY 0.638298 (1025 900);
FORCEPROP 1 LAST PATH I170
J 0
(1025 1250);
DISPLAY 0.978723 (1025 1250);
PAINT WHITE (1025 1250);
DISPLAY INVISIBLE (1025 1250);
FORCEPROP 2 LAST CDS_LIB pure_quanta
J 0
(975 1100);
DISPLAY INVISIBLE (975 1100);
FORCEPROP 1 LAST LOCATION C210
J 0
(1025 1200);
DISPLAY 0.638298 (1025 1200);
FORCEPROP 1 LASTPIN (975 1200) $PN 1
J 0
(985 1180);
DISPLAY 0.787234 (985 1180);
PAINT MONO (985 1180);
FORCEPROP 1 LASTPIN (975 1000) $PN 2
J 0
(985 980);
DISPLAY 0.787234 (985 980);
PAINT MONO (985 980);
FORCEPROP 0 LAST $SEC 1
J 0
(1025 1250);
DISPLAY 0.680851 (1025 1250);
PAINT MONO (1025 1250);
DISPLAY INVISIBLE (1025 1250);
FORCEPROP 0 LAST CDS_SEC 1
J 0
(1025 1250);
DISPLAY 0.680851 (1025 1250);
DISPLAY INVISIBLE (1025 1250);
FORCEADD OFFPAGE..1
(-1950 2725);
FORCEPROP 2 LAST $XR0 15 
J 0
(-2201 2725);
DISPLAY 0.638298 (-2201 2725);
PAINT MONO (-2201 2725);
FORCEPROP 2 LAST PATH I18
J 0
(-2150 2775);
DISPLAY 1.021277 (-2150 2775);
DISPLAY INVISIBLE (-2150 2775);
FORCEPROP 1 LAST COMMENT_BODY TRUE
J 0
(-1825 2625);
DISPLAY 0.851064 (-1825 2625);
PAINT PEACH (-1825 2625);
DISPLAY INVISIBLE (-1825 2625);
FORCEPROP 1 LAST OFFPAGE TRUE
J 0
(-1625 2600);
DISPLAY 0.851064 (-1625 2600);
PAINT GREEN (-1625 2600);
DISPLAY INVISIBLE (-1625 2600);
FORCEPROP 2 LAST CDS_LIB standard
J 0
(-1950 2725);
DISPLAY 0.978723 (-1950 2725);
DISPLAY INVISIBLE (-1950 2725);
FORCEADD Q_RES..1
(-1675 2825);
FORCEPROP 1 LAST MATERIAL CHIP
J 0
(-1550 2825);
DISPLAY 0.510638 (-1550 2825);
PAINT SKYBLUE (-1550 2825);
FORCEPROP 1 LAST VALUE 0
J 2
(-1764 2825);
DISPLAY 0.510638 (-1764 2825);
PAINT SKYBLUE (-1764 2825);
FORCEPROP 1 LAST PART_NUMBER CS00002JB13
J 0
(-1725 2925);
DISPLAY 0.510638 (-1725 2925);
PAINT WHITE (-1725 2925);
DISPLAY INVISIBLE (-1725 2925);
FORCEPROP 1 LAST PACK_TYPE 0402LF
J 0
(-1425 2675);
DISPLAY 0.510638 (-1425 2675);
PAINT SKYBLUE (-1425 2675);
DISPLAY INVISIBLE (-1425 2675);
FORCEPROP 1 LAST WATTAGE 1/16W
J 2
(-1700 2675);
DISPLAY 0.510638 (-1700 2675);
PAINT SKYBLUE (-1700 2675);
DISPLAY INVISIBLE (-1700 2675);
FORCEPROP 1 LAST PATH I19
J 0
(-1725 2975);
DISPLAY 0.978723 (-1725 2975);
PAINT WHITE (-1725 2975);
DISPLAY INVISIBLE (-1725 2975);
FORCEPROP 2 LAST CDS_LIB pure_quanta
J 0
(-1675 2825);
PAINT MONO (-1675 2825);
DISPLAY INVISIBLE (-1675 2825);
FORCEPROP 1 LAST TOLERANCE 5%
J 0
(-1675 2725);
DISPLAY 0.510638 (-1675 2725);
PAINT SKYBLUE (-1675 2725);
DISPLAY INVISIBLE (-1675 2725);
FORCEPROP 1 LAST LOCATION R18
J 0
(-1714 2875);
DISPLAY 0.702128 (-1714 2875);
PAINT YELLOW (-1714 2875);
FORCEPROP 1 LASTPIN (-1775 2825) $PN 1
J 0
(-1763 2837);
DISPLAY 0.808511 (-1763 2837);
PAINT WHITE (-1763 2837);
FORCEPROP 1 LASTPIN (-1575 2825) $PN 2
J 0
(-1613 2837);
DISPLAY 0.808511 (-1613 2837);
PAINT WHITE (-1613 2837);
FORCEPROP 2 LAST $SEC 1
J 0
(-1725 3025);
DISPLAY 0.680851 (-1725 3025);
PAINT MONO (-1725 3025);
DISPLAY INVISIBLE (-1725 3025);
FORCEPROP 2 LAST CDS_SEC 1
J 0
(-1625 3050);
DISPLAY 1.021277 (-1625 3050);
DISPLAY INVISIBLE (-1625 3050);
FORCEADD MOSFET_NCH_DUAL..2
R 5
(500 -725);
FORCEPROP 2 LAST VALUE 2N7002KDW
R 3
J 0
(525 -900);
DISPLAY 0.510638 (525 -900);
PAINT SKYBLUE (525 -900);
FORCEPROP 2 LAST PART_TYPE SMLF
R 3
J 0
(575 -900);
DISPLAY 0.510638 (575 -900);
PAINT SKYBLUE (575 -900);
FORCEPROP 1 LAST MATERIAL IC
R 3
J 0
(351 -876);
DISPLAY 0.510638 (351 -876);
PAINT SKYBLUE (351 -876);
FORCEPROP 1 LAST PART_NUMBER BAM70020047
R 3
J 0
(406 -876);
DISPLAY 0.510638 (406 -876);
PAINT WHITE (406 -876);
FORCEPROP 1 LAST PATH I2
R 3
J 0
(350 -875);
DISPLAY 0.723404 (350 -875);
PAINT GREEN (350 -875);
DISPLAY INVISIBLE (350 -875);
FORCEPROP 2 LAST CDS_LIB pure_quanta
J 0
(500 -725);
DISPLAY INVISIBLE (500 -725);
FORCEPROP 1 LAST CDS_LMAN_SYM_OUTLINE -150,150,150,-150
R 3
J 0
(500 -725);
DISPLAY 0.468085 (500 -725);
PAINT GREEN (500 -725);
DISPLAY INVISIBLE (500 -725);
FORCEPROP 1 LAST NEEDS_NO_SIZE TRUE
R 3
J 0
(391 -875);
DISPLAY 0.468085 (391 -875);
PAINT GREEN (391 -875);
DISPLAY INVISIBLE (391 -875);
FORCEPROP 1 LAST LOCATION Q2
R 3
J 0
(476 -876);
DISPLAY 0.702128 (476 -876);
PAINT YELLOW (476 -876);
FORCEPROP 2 LASTPIN (700 -775) $PN 3
J 0
(710 -765);
DISPLAY 0.808511 (710 -765);
PAINT WHITE (710 -765);
FORCEPROP 2 LASTPIN (450 -525) $PN 5
R 1
J 0
(440 -515);
DISPLAY 0.808511 (440 -515);
PAINT WHITE (440 -515);
FORCEPROP 2 LASTPIN (300 -775) $PN 4
J 2
(290 -765);
DISPLAY 0.808511 (290 -765);
PAINT WHITE (290 -765);
FORCEPROP 2 LAST $SEC 2
J 0
(700 -500);
DISPLAY 0.680851 (700 -500);
PAINT MONO (700 -500);
DISPLAY INVISIBLE (700 -500);
FORCEPROP 2 LAST CDS_SEC 2
J 0
(700 -500);
DISPLAY 0.680851 (700 -500);
DISPLAY INVISIBLE (700 -500);
FORCEADD OFFPAGE..6
(-1900 3100);
FORCEPROP 2 LAST $XR0 23 
J 0
(-2149 3100);
DISPLAY 0.638298 (-2149 3100);
PAINT MONO (-2149 3100);
FORCEPROP 2 LAST PATH I20
J 0
(-2125 3150);
DISPLAY 1.021277 (-2125 3150);
DISPLAY INVISIBLE (-2125 3150);
FORCEPROP 1 LAST COMMENT_BODY TRUE
J 0
(-1800 3025);
DISPLAY 1.574468 (-1800 3025);
PAINT PEACH (-1800 3025);
DISPLAY INVISIBLE (-1800 3025);
FORCEPROP 1 LAST OFFPAGE TRUE
J 0
(-1575 2975);
DISPLAY 1.574468 (-1575 2975);
PAINT GREEN (-1575 2975);
DISPLAY INVISIBLE (-1575 2975);
FORCEPROP 2 LAST CDS_LIB standard
J 0
(-1900 3100);
DISPLAY 0.978723 (-1900 3100);
DISPLAY INVISIBLE (-1900 3100);
FORCEADD OFFPAGE..1
(-1950 3300);
FORCEPROP 2 LAST $XR0 23 
J 0
(-2201 3300);
DISPLAY 0.638298 (-2201 3300);
PAINT MONO (-2201 3300);
FORCEPROP 2 LAST PATH I21
J 0
(-2200 3350);
DISPLAY 1.021277 (-2200 3350);
DISPLAY INVISIBLE (-2200 3350);
FORCEPROP 1 LAST COMMENT_BODY TRUE
J 0
(-1825 3200);
DISPLAY 1.574468 (-1825 3200);
PAINT PEACH (-1825 3200);
DISPLAY INVISIBLE (-1825 3200);
FORCEPROP 1 LAST OFFPAGE TRUE
J 0
(-1625 3175);
DISPLAY 1.574468 (-1625 3175);
PAINT GREEN (-1625 3175);
DISPLAY INVISIBLE (-1625 3175);
FORCEPROP 2 LAST CDS_LIB standard
J 0
(-1950 3300);
DISPLAY 0.978723 (-1950 3300);
DISPLAY INVISIBLE (-1950 3300);
FORCEADD UNIVERSAL_POWER..1
(-1925 2946);
FORCEPROP 3 LASTPIN (-1925 2896) SIG_NAME P5V_AUX\g
J 0
(-1915 2906);
DISPLAY 0.659574 (-1915 2906);
PAINT MONO (-1915 2906);
DISPLAY INVISIBLE (-1915 2906);
FORCEPROP 1 LAST HDL_POWER P5V_AUX
J 1
(-1925 2996);
DISPLAY 0.702128 (-1925 2996);
PAINT RED (-1925 2996);
FORCEPROP 1 LAST PATH I22
J 0
(-1875 2971);
DISPLAY 0.872340 (-1875 2971);
PAINT AQUA (-1875 2971);
DISPLAY INVISIBLE (-1875 2971);
FORCEPROP 2 LAST CDS_LIB logical_power
J 0
(-1925 2946);
PAINT MONO (-1925 2946);
DISPLAY INVISIBLE (-1925 2946);
FORCEADD OFFPAGE..6
(-1775 -425);
FORCEPROP 2 LAST $XR0 15 
J 0
(-2024 -425);
DISPLAY 0.638298 (-2024 -425);
PAINT MONO (-2024 -425);
FORCEPROP 2 LAST PATH I23
J 0
(-1975 -375);
DISPLAY 1.021277 (-1975 -375);
DISPLAY INVISIBLE (-1975 -375);
FORCEPROP 1 LAST COMMENT_BODY TRUE
J 0
(-1675 -500);
DISPLAY 1.319149 (-1675 -500);
PAINT PEACH (-1675 -500);
DISPLAY INVISIBLE (-1675 -500);
FORCEPROP 1 LAST OFFPAGE TRUE
J 0
(-1450 -550);
DISPLAY 1.340425 (-1450 -550);
PAINT GREEN (-1450 -550);
DISPLAY INVISIBLE (-1450 -550);
FORCEPROP 2 LAST ROOM SM_CONTROLLER
J 0
(-2050 -375);
DISPLAY 1.319149 (-2050 -375);
DISPLAY INVISIBLE (-2050 -375);
FORCEPROP 2 LAST CDS_LIB standard
J 0
(-1775 -425);
DISPLAY 2.085106 (-1775 -425);
DISPLAY INVISIBLE (-1775 -425);
FORCEADD UNIVERSAL_GND..1
(-775 650);
FORCEPROP 3 LASTPIN (-775 700) SIG_NAME GND\g
J 0
(-765 710);
DISPLAY 0.659574 (-765 710);
PAINT MONO (-765 710);
DISPLAY INVISIBLE (-765 710);
FORCEPROP 1 LAST PATH I24
J 0
(-700 650);
DISPLAY 0.872340 (-700 650);
PAINT AQUA (-700 650);
DISPLAY INVISIBLE (-700 650);
FORCEPROP 1 LAST HDL_POWER GND
J 1
(-750 575);
DISPLAY 0.702128 (-750 575);
PAINT GREEN (-750 575);
DISPLAY INVISIBLE (-750 575);
FORCEPROP 2 LAST CDS_LIB logical_power
J 0
(-775 650);
DISPLAY INVISIBLE (-775 650);
FORCEADD Q_CAP..1
(-1150 1075);
FORCEPROP 1 LAST VOLTAGE 50V
J 0
(-1100 1075);
DISPLAY 0.510638 (-1100 1075);
PAINT SKYBLUE (-1100 1075);
FORCEPROP 1 LAST MATERIAL C0G
J 0
(-1100 975);
DISPLAY 0.510638 (-1100 975);
PAINT SKYBLUE (-1100 975);
FORCEPROP 1 LAST TOLERANCE 5%
J 0
(-1100 1025);
DISPLAY 0.510638 (-1100 1025);
PAINT SKYBLUE (-1100 1025);
FORCEPROP 1 LAST PACK_TYPE 0402
J 0
(-1100 925);
DISPLAY 0.510638 (-1100 925);
PAINT SKYBLUE (-1100 925);
FORCEPROP 1 LAST VALUE 15PF
J 0
(-1100 1125);
DISPLAY 0.510638 (-1100 1125);
PAINT SKYBLUE (-1100 1125);
FORCEPROP 1 LAST PATH I25
J 0
(-1100 1225);
DISPLAY 0.978723 (-1100 1225);
PAINT WHITE (-1100 1225);
DISPLAY INVISIBLE (-1100 1225);
FORCEPROP 2 LAST CDS_LIB pure_quanta
J 0
(-1150 1075);
DISPLAY INVISIBLE (-1150 1075);
FORCEPROP 1 LAST PART_NUMBER CH01506JB06
J 0
(-1100 925);
DISPLAY 0.510638 (-1100 925);
PAINT WHITE (-1100 925);
DISPLAY INVISIBLE (-1100 925);
FORCEPROP 1 LAST LOCATION C205
J 0
(-1100 1175);
DISPLAY 0.702128 (-1100 1175);
PAINT YELLOW (-1100 1175);
FORCEPROP 1 LASTPIN (-1150 1175) $PN 1
J 0
(-1140 1155);
DISPLAY 0.808511 (-1140 1155);
PAINT WHITE (-1140 1155);
FORCEPROP 1 LASTPIN (-1150 975) $PN 2
J 0
(-1140 955);
DISPLAY 0.808511 (-1140 955);
PAINT WHITE (-1140 955);
FORCEPROP 0 LAST $SEC 1
J 0
(-1100 1225);
DISPLAY 0.680851 (-1100 1225);
PAINT MONO (-1100 1225);
DISPLAY INVISIBLE (-1100 1225);
FORCEPROP 0 LAST CDS_SEC 1
J 0
(-1100 1225);
DISPLAY 0.680851 (-1100 1225);
DISPLAY INVISIBLE (-1100 1225);
FORCEADD Q_CAP..1
(-775 1075);
FORCEPROP 1 LAST MATERIAL C0G
J 0
(-725 975);
DISPLAY 0.510638 (-725 975);
PAINT SKYBLUE (-725 975);
FORCEPROP 1 LAST TOLERANCE 5%
J 0
(-725 1025);
DISPLAY 0.510638 (-725 1025);
PAINT SKYBLUE (-725 1025);
FORCEPROP 1 LAST VALUE 15PF
J 0
(-725 1125);
DISPLAY 0.510638 (-725 1125);
PAINT SKYBLUE (-725 1125);
FORCEPROP 1 LAST VOLTAGE 50V
J 0
(-725 1075);
DISPLAY 0.510638 (-725 1075);
PAINT SKYBLUE (-725 1075);
FORCEPROP 1 LAST PACK_TYPE 0402
J 0
(-725 925);
DISPLAY 0.510638 (-725 925);
PAINT SKYBLUE (-725 925);
FORCEPROP 1 LAST PATH I26
J 0
(-725 1225);
DISPLAY 0.978723 (-725 1225);
PAINT WHITE (-725 1225);
DISPLAY INVISIBLE (-725 1225);
FORCEPROP 2 LAST CDS_LIB pure_quanta
J 0
(-775 1075);
DISPLAY INVISIBLE (-775 1075);
FORCEPROP 1 LAST PART_NUMBER CH01506JB06
J 0
(-725 925);
DISPLAY 0.510638 (-725 925);
PAINT WHITE (-725 925);
DISPLAY INVISIBLE (-725 925);
FORCEPROP 1 LAST LOCATION C206
J 0
(-725 1175);
DISPLAY 0.702128 (-725 1175);
PAINT YELLOW (-725 1175);
FORCEPROP 1 LASTPIN (-775 1175) $PN 1
J 0
(-765 1155);
DISPLAY 0.808511 (-765 1155);
PAINT WHITE (-765 1155);
FORCEPROP 1 LASTPIN (-775 975) $PN 2
J 0
(-765 955);
DISPLAY 0.808511 (-765 955);
PAINT WHITE (-765 955);
FORCEPROP 0 LAST $SEC 1
J 0
(-725 1225);
DISPLAY 0.680851 (-725 1225);
PAINT MONO (-725 1225);
DISPLAY INVISIBLE (-725 1225);
FORCEPROP 0 LAST CDS_SEC 1
J 0
(-725 1225);
DISPLAY 0.680851 (-725 1225);
DISPLAY INVISIBLE (-725 1225);
FORCEADD Q_RES..2
(-1100 -200);
FORCEPROP 1 LAST TOLERANCE 1%
J 2
(-1125 -200);
DISPLAY 0.510638 (-1125 -200);
PAINT SKYBLUE (-1125 -200);
FORCEPROP 1 LAST PACK_TYPE 0402LF
J 2
(-1125 -350);
DISPLAY 0.510638 (-1125 -350);
PAINT SKYBLUE (-1125 -350);
FORCEPROP 1 LAST MATERIAL CHIP
J 2
(-1125 -300);
DISPLAY 0.510638 (-1125 -300);
PAINT SKYBLUE (-1125 -300);
FORCEPROP 1 LAST WATTAGE 1/16W
J 2
(-1125 -250);
DISPLAY 0.510638 (-1125 -250);
PAINT SKYBLUE (-1125 -250);
FORCEPROP 1 LAST VALUE 4.7K
J 2
(-1125 -150);
DISPLAY 0.510638 (-1125 -150);
PAINT SKYBLUE (-1125 -150);
FORCEPROP 1 LAST PART_NUMBER CS24702FB06
J 0
(-1060 -325);
DISPLAY 0.510638 (-1060 -325);
PAINT WHITE (-1060 -325);
DISPLAY INVISIBLE (-1060 -325);
FORCEPROP 1 LAST PATH I27
J 0
(-1050 -25);
DISPLAY 0.978723 (-1050 -25);
PAINT WHITE (-1050 -25);
DISPLAY INVISIBLE (-1050 -25);
FORCEPROP 2 LAST CDS_LIB pure_quanta
J 0
(-1100 -200);
DISPLAY INVISIBLE (-1100 -200);
FORCEPROP 1 LAST LOCATION R31
J 2
(-1125 -100);
DISPLAY 0.702128 (-1125 -100);
PAINT YELLOW (-1125 -100);
FORCEPROP 1 LASTPIN (-1100 -100) $PN 1
J 0
(-1095 -138);
DISPLAY 0.808511 (-1095 -138);
PAINT WHITE (-1095 -138);
FORCEPROP 1 LASTPIN (-1100 -300) $PN 2
J 0
(-1095 -290);
DISPLAY 0.808511 (-1095 -290);
PAINT WHITE (-1095 -290);
FORCEPROP 2 LAST $SEC 1
J 0
(-1050 25);
DISPLAY 0.680851 (-1050 25);
PAINT MONO (-1050 25);
DISPLAY INVISIBLE (-1050 25);
FORCEPROP 2 LAST CDS_SEC 1
J 0
(-1050 25);
DISPLAY 0.680851 (-1050 25);
DISPLAY INVISIBLE (-1050 25);
FORCEADD UNIVERSAL_POWER..1
(-1100 150);
FORCEPROP 3 LASTPIN (-1100 100) SIG_NAME P3V3_RGM\g
J 0
(-1090 110);
DISPLAY 0.659574 (-1090 110);
PAINT MONO (-1090 110);
DISPLAY INVISIBLE (-1090 110);
FORCEPROP 1 LAST HDL_POWER P3V3_RGM
J 1
(-1100 200);
DISPLAY 0.702128 (-1100 200);
PAINT GREEN (-1100 200);
FORCEPROP 1 LAST PATH I28
J 0
(-1050 175);
DISPLAY 0.872340 (-1050 175);
PAINT AQUA (-1050 175);
DISPLAY INVISIBLE (-1050 175);
FORCEPROP 2 LAST CDS_LIB logical_power
J 0
(-1100 150);
PAINT MONO (-1100 150);
DISPLAY INVISIBLE (-1100 150);
FORCEADD Q_CAP..1
(-425 1075);
FORCEPROP 1 LAST TOLERANCE 5%
J 0
(-375 1025);
DISPLAY 0.510638 (-375 1025);
PAINT SKYBLUE (-375 1025);
FORCEPROP 1 LAST VOLTAGE 50V
J 0
(-375 1075);
DISPLAY 0.510638 (-375 1075);
PAINT SKYBLUE (-375 1075);
FORCEPROP 1 LAST VALUE 15PF
J 0
(-375 1125);
DISPLAY 0.510638 (-375 1125);
PAINT SKYBLUE (-375 1125);
FORCEPROP 1 LAST MATERIAL C0G
J 0
(-375 975);
DISPLAY 0.510638 (-375 975);
PAINT SKYBLUE (-375 975);
FORCEPROP 1 LAST PACK_TYPE 0402
J 0
(-375 925);
DISPLAY 0.510638 (-375 925);
PAINT SKYBLUE (-375 925);
FORCEPROP 2 LAST CDS_LIB pure_quanta
J 0
(-425 1075);
DISPLAY INVISIBLE (-425 1075);
FORCEPROP 1 LAST PATH I29
J 0
(-375 1225);
DISPLAY 0.978723 (-375 1225);
PAINT WHITE (-375 1225);
DISPLAY INVISIBLE (-375 1225);
FORCEPROP 1 LAST PART_NUMBER CH01506JB06
J 0
(-375 925);
DISPLAY 0.510638 (-375 925);
PAINT WHITE (-375 925);
DISPLAY INVISIBLE (-375 925);
FORCEPROP 1 LAST LOCATION C207
J 0
(-375 1175);
DISPLAY 0.702128 (-375 1175);
PAINT YELLOW (-375 1175);
FORCEPROP 1 LASTPIN (-425 1175) $PN 1
J 0
(-415 1155);
DISPLAY 0.808511 (-415 1155);
PAINT WHITE (-415 1155);
FORCEPROP 1 LASTPIN (-425 975) $PN 2
J 0
(-415 955);
DISPLAY 0.808511 (-415 955);
PAINT WHITE (-415 955);
FORCEPROP 0 LAST $SEC 1
J 0
(-375 1225);
DISPLAY 0.680851 (-375 1225);
PAINT MONO (-375 1225);
DISPLAY INVISIBLE (-375 1225);
FORCEPROP 0 LAST CDS_SEC 1
J 0
(-375 1225);
DISPLAY 0.680851 (-375 1225);
DISPLAY INVISIBLE (-375 1225);
FORCEADD OFFPAGE..2
(2075 -775);
FORCEPROP 2 LAST $XR0 23 
J 0
(2264 -775);
DISPLAY 0.638298 (2264 -775);
PAINT MONO (2264 -775);
FORCEPROP 2 LAST PATH I3
J 0
(2275 -725);
DISPLAY 1.021277 (2275 -725);
DISPLAY INVISIBLE (2275 -725);
FORCEPROP 1 LAST COMMENT_BODY TRUE
J 0
(2030 -870);
DISPLAY 1.319149 (2030 -870);
PAINT PEACH (2030 -870);
DISPLAY INVISIBLE (2030 -870);
FORCEPROP 1 LAST OFFPAGE TRUE
J 0
(2400 -900);
DISPLAY 1.340425 (2400 -900);
PAINT GREEN (2400 -900);
DISPLAY INVISIBLE (2400 -900);
FORCEPROP 2 LAST ROOM SM_CONTROLLER
J 0
(1800 -725);
DISPLAY 1.319149 (1800 -725);
DISPLAY INVISIBLE (1800 -725);
FORCEPROP 2 LAST CDS_LIB standard
J 0
(2075 -775);
DISPLAY 2.085106 (2075 -775);
DISPLAY INVISIBLE (2075 -775);
FORCEADD UNIVERSAL_GND..1
(-1475 2100);
FORCEPROP 3 LASTPIN (-1475 2150) SIG_NAME GND\g
J 0
(-1465 2160);
DISPLAY 0.659574 (-1465 2160);
PAINT MONO (-1465 2160);
DISPLAY INVISIBLE (-1465 2160);
FORCEPROP 1 LAST PATH I31
J 0
(-1400 2100);
DISPLAY 0.872340 (-1400 2100);
PAINT AQUA (-1400 2100);
DISPLAY INVISIBLE (-1400 2100);
FORCEPROP 1 LAST HDL_POWER GND
J 1
(-1450 2025);
DISPLAY 0.702128 (-1450 2025);
PAINT GREEN (-1450 2025);
DISPLAY INVISIBLE (-1450 2025);
FORCEPROP 2 LAST CDS_LIB logical_power
J 0
(-1475 2100);
DISPLAY INVISIBLE (-1475 2100);
FORCEADD 74HC1G126GW..1
(-625 2325);
FORCEPROP 2 LAST PART_TYPE SMLF
J 0
(-525 2550);
DISPLAY 0.510638 (-525 2550);
PAINT SKYBLUE (-525 2550);
FORCEPROP 1 LAST MATERIAL IC
J 0
(-525 2425);
DISPLAY 0.510638 (-525 2425);
PAINT SKYBLUE (-525 2425);
FORCEPROP 2 LAST VALUE 74HC1G126GW
J 0
(-525 2500);
DISPLAY 0.510638 (-525 2500);
PAINT SKYBLUE (-525 2500);
FORCEPROP 1 LAST PATH I32
J 0
(-625 2325);
DISPLAY 0.723404 (-625 2325);
PAINT GREEN (-625 2325);
DISPLAY INVISIBLE (-625 2325);
FORCEPROP 1 LAST PART_NUMBER AL1G0126007
J 0
(-385 2137);
DISPLAY 0.510638 (-385 2137);
PAINT WHITE (-385 2137);
DISPLAY INVISIBLE (-385 2137);
FORCEPROP 1 LAST NEEDS_NO_SIZE TRUE
J 0
(-625 2325);
DISPLAY 0.723404 (-625 2325);
PAINT GREEN (-625 2325);
DISPLAY INVISIBLE (-625 2325);
FORCEPROP 1 LAST CDS_LMAN_SYM_OUTLINE -100,100,100,-100
J 0
(-625 2325);
DISPLAY 0.468085 (-625 2325);
PAINT GREEN (-625 2325);
DISPLAY INVISIBLE (-625 2325);
FORCEPROP 2 LAST CDS_LIB pure_quanta
J 0
(-625 2325);
DISPLAY INVISIBLE (-625 2325);
FORCEPROP 1 LAST LOCATION U33
J 0
(-525 2462);
DISPLAY 0.702128 (-525 2462);
PAINT YELLOW (-525 2462);
FORCEPROP 2 LASTPIN (-625 2575) $PN 1
R 1
J 0
(-635 2585);
DISPLAY 0.808511 (-635 2585);
PAINT WHITE (-635 2585);
FORCEPROP 2 LASTPIN (-875 2325) $PN 2
J 2
(-885 2335);
DISPLAY 0.808511 (-885 2335);
PAINT WHITE (-885 2335);
FORCEPROP 2 LASTPIN (-375 2325) $PN 4
J 0
(-365 2335);
DISPLAY 0.808511 (-365 2335);
PAINT WHITE (-365 2335);
FORCEPROP 2 LASTPIN (-775 2425) $PN 5
J 2
(-785 2435);
DISPLAY 0.808511 (-785 2435);
PAINT WHITE (-785 2435);
FORCEPROP 2 LASTPIN (-775 2225) $PN 3
J 2
(-785 2235);
DISPLAY 0.808511 (-785 2235);
PAINT WHITE (-785 2235);
FORCEPROP 2 LAST $SEC 1
J 0
(-625 2375);
DISPLAY 0.680851 (-625 2375);
PAINT MONO (-625 2375);
DISPLAY INVISIBLE (-625 2375);
FORCEPROP 2 LAST CDS_SEC 1
J 0
(-625 2375);
DISPLAY 0.680851 (-625 2375);
DISPLAY INVISIBLE (-625 2375);
FORCEADD 74HC1G126GW..1
(-1025 2725);
FORCEPROP 1 LAST PART_NUMBER AL1G0126007
J 0
(-950 2800);
DISPLAY 0.510638 (-950 2800);
PAINT WHITE (-950 2800);
FORCEPROP 2 LAST VALUE 74HC1G126GW
J 0
(-950 2888);
DISPLAY 0.510638 (-950 2888);
PAINT SKYBLUE (-950 2888);
FORCEPROP 2 LAST PART_TYPE SMLF
J 0
(-950 2938);
DISPLAY 0.510638 (-950 2938);
PAINT SKYBLUE (-950 2938);
FORCEPROP 1 LAST MATERIAL IC
J 0
(-785 2458);
DISPLAY 0.510638 (-785 2458);
PAINT SKYBLUE (-785 2458);
FORCEPROP 1 LAST PATH I33
J 0
(-1025 2725);
DISPLAY 0.723404 (-1025 2725);
PAINT GREEN (-1025 2725);
DISPLAY INVISIBLE (-1025 2725);
FORCEPROP 1 LAST NEEDS_NO_SIZE TRUE
J 0
(-1025 2725);
DISPLAY 0.723404 (-1025 2725);
PAINT GREEN (-1025 2725);
DISPLAY INVISIBLE (-1025 2725);
FORCEPROP 1 LAST CDS_LMAN_SYM_OUTLINE -100,100,100,-100
J 0
(-1025 2725);
DISPLAY 0.468085 (-1025 2725);
PAINT GREEN (-1025 2725);
DISPLAY INVISIBLE (-1025 2725);
FORCEPROP 2 LAST CDS_LIB pure_quanta
J 0
(-1025 2725);
DISPLAY INVISIBLE (-1025 2725);
FORCEPROP 1 LAST LOCATION U26
J 0
(-950 2850);
DISPLAY 0.702128 (-950 2850);
PAINT YELLOW (-950 2850);
FORCEPROP 2 LASTPIN (-1025 2975) $PN 1
R 1
J 0
(-1035 2985);
DISPLAY 0.808511 (-1035 2985);
PAINT WHITE (-1035 2985);
FORCEPROP 2 LASTPIN (-1275 2725) $PN 2
J 2
(-1285 2735);
DISPLAY 0.808511 (-1285 2735);
PAINT WHITE (-1285 2735);
FORCEPROP 2 LASTPIN (-775 2725) $PN 4
J 0
(-765 2735);
DISPLAY 0.808511 (-765 2735);
PAINT WHITE (-765 2735);
FORCEPROP 2 LASTPIN (-1175 2825) $PN 5
J 2
(-1185 2835);
DISPLAY 0.808511 (-1185 2835);
PAINT WHITE (-1185 2835);
FORCEPROP 2 LASTPIN (-1175 2625) $PN 3
J 2
(-1185 2635);
DISPLAY 0.808511 (-1185 2635);
PAINT WHITE (-1185 2635);
FORCEPROP 2 LAST $SEC 1
J 0
(-1025 2775);
DISPLAY 0.680851 (-1025 2775);
PAINT MONO (-1025 2775);
DISPLAY INVISIBLE (-1025 2775);
FORCEPROP 2 LAST CDS_SEC 1
J 0
(-1025 2775);
DISPLAY 0.680851 (-1025 2775);
DISPLAY INVISIBLE (-1025 2775);
FORCEADD Q_RES..1
(-925 3100);
FORCEPROP 1 LAST VALUE 33.2
J 2
(-725 3100);
DISPLAY 0.510638 (-725 3100);
PAINT SKYBLUE (-725 3100);
FORCEPROP 1 LAST MATERIAL CHIP
J 0
(-825 3075);
DISPLAY 0.510638 (-825 3075);
PAINT SKYBLUE (-825 3075);
FORCEPROP 1 LAST TOLERANCE 1%
J 0
(-925 3000);
DISPLAY 0.510638 (-925 3000);
PAINT SKYBLUE (-925 3000);
DISPLAY INVISIBLE (-925 3000);
FORCEPROP 1 LAST PART_NUMBER CS03322FB03
J 0
(-975 3200);
DISPLAY 0.510638 (-975 3200);
PAINT WHITE (-975 3200);
DISPLAY INVISIBLE (-975 3200);
FORCEPROP 1 LAST PACK_TYPE 0402LF
J 0
(-675 2950);
DISPLAY 0.510638 (-675 2950);
PAINT SKYBLUE (-675 2950);
DISPLAY INVISIBLE (-675 2950);
FORCEPROP 1 LAST WATTAGE 1/16W
J 2
(-950 2950);
DISPLAY 0.510638 (-950 2950);
PAINT SKYBLUE (-950 2950);
DISPLAY INVISIBLE (-950 2950);
FORCEPROP 1 LAST PATH I34
J 0
(-975 3250);
DISPLAY 0.978723 (-975 3250);
PAINT WHITE (-975 3250);
DISPLAY INVISIBLE (-975 3250);
FORCEPROP 2 LAST CDS_LIB pure_quanta
J 0
(-925 3100);
DISPLAY 1.340425 (-925 3100);
DISPLAY INVISIBLE (-925 3100);
FORCEPROP 1 LAST LOCATION R29
J 0
(-980 3130);
DISPLAY 0.702128 (-980 3130);
PAINT YELLOW (-980 3130);
FORCEPROP 1 LASTPIN (-1025 3100) $PN 1
J 0
(-1013 3112);
DISPLAY 0.808511 (-1013 3112);
PAINT WHITE (-1013 3112);
FORCEPROP 1 LASTPIN (-825 3100) $PN 2
J 0
(-863 3112);
DISPLAY 0.808511 (-863 3112);
PAINT WHITE (-863 3112);
FORCEPROP 2 LAST $SEC 1
J 0
(-975 3350);
DISPLAY 0.680851 (-975 3350);
PAINT MONO (-975 3350);
DISPLAY INVISIBLE (-975 3350);
FORCEPROP 2 LAST CDS_SEC 1
J 0
(-975 3350);
DISPLAY 1.021277 (-975 3350);
DISPLAY INVISIBLE (-975 3350);
FORCEADD Q_RES..2
R 2
(-450 3475);
FORCEPROP 1 LAST PACK_TYPE 0402LF
J 2
(-490 3360);
DISPLAY 0.510638 (-490 3360);
PAINT SKYBLUE (-490 3360);
FORCEPROP 1 LAST WATTAGE 1/16W
J 2
(-490 3460);
DISPLAY 0.510638 (-490 3460);
PAINT SKYBLUE (-490 3460);
FORCEPROP 1 LAST MATERIAL CHIP
J 2
(-490 3410);
DISPLAY 0.510638 (-490 3410);
PAINT SKYBLUE (-490 3410);
FORCEPROP 1 LAST VALUE 0
J 2
(-490 3570);
DISPLAY 0.510638 (-490 3570);
PAINT SKYBLUE (-490 3570);
FORCEPROP 1 LAST TOLERANCE 5%
J 2
(-490 3510);
DISPLAY 0.510638 (-490 3510);
PAINT SKYBLUE (-490 3510);
FORCEPROP 1 LAST PART_NUMBER CS00002JB13
J 2
(-490 3350);
DISPLAY 0.510638 (-490 3350);
PAINT WHITE (-490 3350);
DISPLAY INVISIBLE (-490 3350);
FORCEPROP 1 LAST PATH I39
J 2
(-500 3650);
DISPLAY 0.978723 (-500 3650);
PAINT WHITE (-500 3650);
DISPLAY INVISIBLE (-500 3650);
FORCEPROP 2 LAST CDS_LIB pure_quanta
J 2
(-450 3475);
PAINT MONO (-450 3475);
DISPLAY INVISIBLE (-450 3475);
FORCEPROP 1 LAST LOCATION R30
J 2
(-490 3620);
DISPLAY 0.702128 (-490 3620);
PAINT YELLOW (-490 3620);
FORCEPROP 1 LASTPIN (-450 3575) $PN 1
J 2
(-455 3537);
DISPLAY 0.808511 (-455 3537);
PAINT WHITE (-455 3537);
FORCEPROP 1 LASTPIN (-450 3375) $PN 2
J 2
(-455 3385);
DISPLAY 0.808511 (-455 3385);
PAINT WHITE (-455 3385);
FORCEPROP 2 LAST $SEC 1
J 2
(-500 3700);
DISPLAY 0.680851 (-500 3700);
PAINT MONO (-500 3700);
DISPLAY INVISIBLE (-500 3700);
FORCEPROP 2 LAST CDS_SEC 1
J 2
(-500 3700);
DISPLAY 1.021277 (-500 3700);
DISPLAY INVISIBLE (-500 3700);
FORCEADD Q_RES..1
(-1875 4075);
FORCEPROP 1 LAST PART_NUMBER CS00003J910
J 0
(-2050 3975);
DISPLAY 0.510638 (-2050 3975);
PAINT WHITE (-2050 3975);
FORCEPROP 1 LAST VALUE 0
J 2
(-2000 4075);
DISPLAY 0.510638 (-2000 4075);
PAINT SKYBLUE (-2000 4075);
FORCEPROP 1 LAST TOLERANCE 5%
J 0
(-1725 4075);
DISPLAY 0.510638 (-1725 4075);
PAINT SKYBLUE (-1725 4075);
FORCEPROP 1 LAST MATERIAL EMPTY
J 0
(-2000 4025);
DISPLAY 0.510638 (-2000 4025);
PAINT RED (-2000 4025);
FORCEPROP 1 LAST PACK_TYPE 0603LF
J 0
(-1825 4025);
DISPLAY 0.510638 (-1825 4025);
PAINT SKYBLUE (-1825 4025);
FORCEPROP 1 LAST PATH I40
J 0
(-1925 4225);
DISPLAY 0.978723 (-1925 4225);
PAINT WHITE (-1925 4225);
DISPLAY INVISIBLE (-1925 4225);
FORCEPROP 1 LAST WATTAGE 1/10W
J 2
(-1900 3925);
DISPLAY 0.510638 (-1900 3925);
PAINT SKYBLUE (-1900 3925);
DISPLAY INVISIBLE (-1900 3925);
FORCEPROP 2 LAST CDS_LIB pure_quanta
J 0
(-1875 4075);
PAINT MONO (-1875 4075);
DISPLAY INVISIBLE (-1875 4075);
FORCEPROP 1 LAST LOCATION R27
J 0
(-1925 4125);
DISPLAY 0.702128 (-1925 4125);
PAINT YELLOW (-1925 4125);
FORCEPROP 1 LASTPIN (-1975 4075) $PN 1
J 0
(-1963 4087);
DISPLAY 0.808511 (-1963 4087);
PAINT WHITE (-1963 4087);
FORCEPROP 1 LASTPIN (-1775 4075) $PN 2
J 0
(-1813 4087);
DISPLAY 0.808511 (-1813 4087);
PAINT WHITE (-1813 4087);
FORCEPROP 2 LAST $SEC 1
J 0
(-1925 4275);
DISPLAY 0.680851 (-1925 4275);
PAINT MONO (-1925 4275);
DISPLAY INVISIBLE (-1925 4275);
FORCEPROP 0 LAST CDS_SEC 1
J 0
(-1925 4275);
DISPLAY 0.680851 (-1925 4275);
PAINT MONO (-1925 4275);
DISPLAY INVISIBLE (-1925 4275);
FORCEADD SCHOTTKY_AC..1
(-1850 4275);
FORCEPROP 2 LAST PART_TYPE SMLF
J 0
(-1925 4550);
DISPLAY 0.510638 (-1925 4550);
PAINT SKYBLUE (-1925 4550);
FORCEPROP 2 LAST VALUE SS0530
J 0
(-1925 4500);
DISPLAY 0.510638 (-1925 4500);
PAINT SKYBLUE (-1925 4500);
FORCEPROP 1 LAST PART_NUMBER BCSS0530Z00
J 0
(-1925 4400);
DISPLAY 0.510638 (-1925 4400);
PAINT WHITE (-1925 4400);
FORCEPROP 1 LAST MATERIAL IC
J 0
(-1925 4350);
DISPLAY 0.510638 (-1925 4350);
PAINT SKYBLUE (-1925 4350);
FORCEPROP 1 LAST PATH I41
J 0
(-1850 4275);
DISPLAY 0.723404 (-1850 4275);
PAINT GREEN (-1850 4275);
DISPLAY INVISIBLE (-1850 4275);
FORCEPROP 1 LAST NEEDS_NO_SIZE TRUE
J 0
(-1775 4225);
DISPLAY 0.468085 (-1775 4225);
PAINT GREEN (-1775 4225);
DISPLAY INVISIBLE (-1775 4225);
FORCEPROP 1 LAST CDS_LMAN_SYM_OUTLINE -75,50,75,-50
J 0
(-1850 4275);
DISPLAY 0.468085 (-1850 4275);
PAINT GREEN (-1850 4275);
DISPLAY INVISIBLE (-1850 4275);
FORCEPROP 2 LAST CDS_LIB pure_quanta
J 0
(-1850 4275);
DISPLAY INVISIBLE (-1850 4275);
FORCEPROP 1 LAST LOCATION D11
J 0
(-1925 4450);
DISPLAY 0.702128 (-1925 4450);
PAINT YELLOW (-1925 4450);
FORCEPROP 2 LASTPIN (-1975 4275) $PN A
J 2
(-1985 4285);
DISPLAY 0.808511 (-1985 4285);
PAINT WHITE (-1985 4285);
FORCEPROP 2 LASTPIN (-1725 4275) $PN C
J 0
(-1715 4285);
DISPLAY 0.808511 (-1715 4285);
PAINT WHITE (-1715 4285);
FORCEPROP 2 LAST $SEC 1
J 0
(-1925 4600);
DISPLAY 0.680851 (-1925 4600);
PAINT MONO (-1925 4600);
DISPLAY INVISIBLE (-1925 4600);
FORCEPROP 0 LAST CDS_SEC 1
J 0
(-1925 4600);
DISPLAY 0.680851 (-1925 4600);
PAINT MONO (-1925 4600);
DISPLAY INVISIBLE (-1925 4600);
FORCEADD SCHOTTKY_AC..1
(-1900 4675);
FORCEPROP 1 LAST PART_NUMBER BCSS0530Z00
J 0
(-1975 4800);
DISPLAY 0.510638 (-1975 4800);
PAINT WHITE (-1975 4800);
FORCEPROP 2 LAST VALUE SS0530
J 0
(-1975 4900);
DISPLAY 0.510638 (-1975 4900);
PAINT SKYBLUE (-1975 4900);
FORCEPROP 2 LAST PART_TYPE SMLF
J 0
(-1975 4950);
DISPLAY 0.510638 (-1975 4950);
PAINT SKYBLUE (-1975 4950);
FORCEPROP 1 LAST MATERIAL EMPTY
J 0
(-1975 4750);
DISPLAY 0.510638 (-1975 4750);
PAINT RED (-1975 4750);
FORCEPROP 1 LAST PATH I42
J 0
(-1900 4675);
DISPLAY 0.723404 (-1900 4675);
PAINT GREEN (-1900 4675);
DISPLAY INVISIBLE (-1900 4675);
FORCEPROP 1 LAST NEEDS_NO_SIZE TRUE
J 0
(-1825 4625);
DISPLAY 0.468085 (-1825 4625);
PAINT GREEN (-1825 4625);
DISPLAY INVISIBLE (-1825 4625);
FORCEPROP 1 LAST CDS_LMAN_SYM_OUTLINE -75,50,75,-50
J 0
(-1900 4675);
DISPLAY 0.468085 (-1900 4675);
PAINT GREEN (-1900 4675);
DISPLAY INVISIBLE (-1900 4675);
FORCEPROP 2 LAST CDS_LIB pure_quanta
J 0
(-1900 4675);
DISPLAY INVISIBLE (-1900 4675);
FORCEPROP 1 LAST LOCATION D9
J 0
(-1975 4850);
DISPLAY 0.702128 (-1975 4850);
PAINT YELLOW (-1975 4850);
FORCEPROP 0 LASTPIN (-2025 4675) $PN A
J 2
(-2035 4685);
DISPLAY 0.808511 (-2035 4685);
PAINT WHITE (-2035 4685);
FORCEPROP 0 LASTPIN (-1775 4675) $PN C
J 0
(-1765 4685);
DISPLAY 0.808511 (-1765 4685);
PAINT WHITE (-1765 4685);
FORCEPROP 0 LAST $SEC 1
J 0
(-1975 5000);
DISPLAY 0.680851 (-1975 5000);
PAINT MONO (-1975 5000);
DISPLAY INVISIBLE (-1975 5000);
FORCEPROP 0 LAST CDS_SEC 1
J 0
(-1975 5000);
DISPLAY 0.680851 (-1975 5000);
DISPLAY INVISIBLE (-1975 5000);
FORCEADD UNIVERSAL_GND..1
(-1425 3625);
FORCEPROP 3 LASTPIN (-1425 3675) SIG_NAME GND\g
J 0
(-1415 3685);
DISPLAY 0.659574 (-1415 3685);
PAINT MONO (-1415 3685);
DISPLAY INVISIBLE (-1415 3685);
FORCEPROP 1 LAST PATH I44
J 0
(-1350 3625);
DISPLAY 0.872340 (-1350 3625);
PAINT AQUA (-1350 3625);
DISPLAY INVISIBLE (-1350 3625);
FORCEPROP 1 LAST HDL_POWER GND
J 1
(-1400 3550);
DISPLAY 0.702128 (-1400 3550);
PAINT GREEN (-1400 3550);
DISPLAY INVISIBLE (-1400 3550);
FORCEPROP 2 LAST CDS_LIB logical_power
J 0
(-1425 3625);
DISPLAY INVISIBLE (-1425 3625);
FORCEADD Q_CAP..1
(-1425 3875);
FORCEPROP 1 LAST VALUE 1UF
J 0
(-1375 3925);
DISPLAY 0.510638 (-1375 3925);
PAINT SKYBLUE (-1375 3925);
FORCEPROP 1 LAST MATERIAL EMPTY
J 0
(-1375 3775);
DISPLAY 0.510638 (-1375 3775);
PAINT RED (-1375 3775);
FORCEPROP 1 LAST PACK_TYPE 0603
J 0
(-1375 3725);
DISPLAY 0.510638 (-1375 3725);
PAINT SKYBLUE (-1375 3725);
FORCEPROP 1 LAST TOLERANCE 10%
J 0
(-1375 3825);
DISPLAY 0.510638 (-1375 3825);
PAINT SKYBLUE (-1375 3825);
FORCEPROP 1 LAST VOLTAGE 16V
J 0
(-1375 3875);
DISPLAY 0.510638 (-1375 3875);
PAINT SKYBLUE (-1375 3875);
FORCEPROP 1 LAST PATH I45
J 0
(-1375 4025);
DISPLAY 0.978723 (-1375 4025);
PAINT WHITE (-1375 4025);
DISPLAY INVISIBLE (-1375 4025);
FORCEPROP 1 LAST PART_NUMBER TMP_QCH5103K1900
J 0
(-1375 3730);
DISPLAY 0.510638 (-1375 3730);
PAINT WHITE (-1375 3730);
DISPLAY INVISIBLE (-1375 3730);
FORCEPROP 2 LAST CDS_LIB pure_quanta
J 0
(-1425 3875);
DISPLAY 1.340425 (-1425 3875);
DISPLAY INVISIBLE (-1425 3875);
FORCEPROP 1 LAST LOCATION C204
J 0
(-1375 3975);
DISPLAY 0.702128 (-1375 3975);
PAINT YELLOW (-1375 3975);
FORCEPROP 1 LASTPIN (-1425 3975) $PN 1
J 0
(-1415 3955);
DISPLAY 0.808511 (-1415 3955);
PAINT WHITE (-1415 3955);
FORCEPROP 1 LASTPIN (-1425 3775) $PN 2
J 0
(-1415 3755);
DISPLAY 0.808511 (-1415 3755);
PAINT WHITE (-1415 3755);
FORCEPROP 2 LAST $SEC 1
J 0
(-1375 4125);
DISPLAY 0.680851 (-1375 4125);
PAINT MONO (-1375 4125);
DISPLAY INVISIBLE (-1375 4125);
FORCEPROP 2 LAST CDS_SEC 1
J 0
(-1375 4125);
DISPLAY 1.021277 (-1375 4125);
DISPLAY INVISIBLE (-1375 4125);
FORCEADD UNIVERSAL_POWER..1
(-1425 4825);
FORCEPROP 3 LASTPIN (-1425 4775) SIG_NAME CRT_VCC5\g
J 0
(-1415 4785);
DISPLAY 0.659574 (-1415 4785);
PAINT MONO (-1415 4785);
DISPLAY INVISIBLE (-1415 4785);
FORCEPROP 1 LAST HDL_POWER CRT_VCC5
J 1
(-1425 4875);
DISPLAY 0.702128 (-1425 4875);
PAINT GREEN (-1425 4875);
FORCEPROP 1 LAST PATH I46
J 0
(-1375 4850);
DISPLAY 0.872340 (-1375 4850);
PAINT AQUA (-1375 4850);
DISPLAY INVISIBLE (-1375 4850);
FORCEPROP 2 LAST CDS_LIB logical_power
J 0
(-1425 4825);
DISPLAY 1.340425 (-1425 4825);
DISPLAY INVISIBLE (-1425 4825);
FORCEADD UNIVERSAL_POWER..1
(-450 3700);
FORCEPROP 3 LASTPIN (-450 3650) SIG_NAME CRT_VCC5\g
J 0
(-440 3660);
DISPLAY 0.659574 (-440 3660);
PAINT MONO (-440 3660);
DISPLAY INVISIBLE (-440 3660);
FORCEPROP 1 LAST HDL_POWER CRT_VCC5
J 1
(-450 3750);
DISPLAY 0.702128 (-450 3750);
PAINT GREEN (-450 3750);
FORCEPROP 1 LAST PATH I47
J 0
(-400 3725);
DISPLAY 0.872340 (-400 3725);
PAINT AQUA (-400 3725);
DISPLAY INVISIBLE (-400 3725);
FORCEPROP 2 LAST CDS_LIB logical_power
J 0
(-450 3700);
DISPLAY INVISIBLE (-450 3700);
FORCEADD Q_RES..2
(-800 -200);
FORCEPROP 1 LAST WATTAGE 1/16W
J 0
(-755 -250);
DISPLAY 0.510638 (-755 -250);
PAINT SKYBLUE (-755 -250);
FORCEPROP 1 LAST MATERIAL CHIP
J 0
(-755 -300);
DISPLAY 0.510638 (-755 -300);
PAINT SKYBLUE (-755 -300);
FORCEPROP 1 LAST VALUE 4.7K
J 0
(-750 -150);
DISPLAY 0.510638 (-750 -150);
PAINT SKYBLUE (-750 -150);
FORCEPROP 1 LAST PACK_TYPE 0402LF
J 0
(-755 -350);
DISPLAY 0.510638 (-755 -350);
PAINT SKYBLUE (-755 -350);
FORCEPROP 1 LAST TOLERANCE 1%
J 0
(-750 -200);
DISPLAY 0.510638 (-750 -200);
PAINT SKYBLUE (-750 -200);
FORCEPROP 1 LAST PART_NUMBER CS24702FB06
J 0
(-760 -325);
DISPLAY 0.510638 (-760 -325);
PAINT WHITE (-760 -325);
DISPLAY INVISIBLE (-760 -325);
FORCEPROP 1 LAST PATH I50
J 0
(-750 -25);
DISPLAY 0.978723 (-750 -25);
PAINT WHITE (-750 -25);
DISPLAY INVISIBLE (-750 -25);
FORCEPROP 2 LAST CDS_LIB pure_quanta
J 0
(-800 -200);
DISPLAY INVISIBLE (-800 -200);
FORCEPROP 1 LAST LOCATION R32
J 0
(-750 -100);
DISPLAY 0.702128 (-750 -100);
PAINT YELLOW (-750 -100);
FORCEPROP 1 LASTPIN (-800 -100) $PN 1
J 0
(-795 -138);
DISPLAY 0.808511 (-795 -138);
PAINT WHITE (-795 -138);
FORCEPROP 1 LASTPIN (-800 -300) $PN 2
J 0
(-795 -290);
DISPLAY 0.808511 (-795 -290);
PAINT WHITE (-795 -290);
FORCEPROP 2 LAST $SEC 1
J 0
(-750 25);
DISPLAY 0.680851 (-750 25);
PAINT MONO (-750 25);
DISPLAY INVISIBLE (-750 25);
FORCEPROP 2 LAST CDS_SEC 1
J 0
(-750 25);
DISPLAY 0.680851 (-750 25);
DISPLAY INVISIBLE (-750 25);
FORCEADD Q_RES..1
(-350 -50);
FORCEPROP 1 LAST MATERIAL CHIP
J 0
(-400 -100);
DISPLAY 0.510638 (-400 -100);
PAINT SKYBLUE (-400 -100);
FORCEPROP 1 LAST VALUE 0
J 2
(-450 -50);
DISPLAY 0.510638 (-450 -50);
PAINT SKYBLUE (-450 -50);
FORCEPROP 1 LAST PART_NUMBER CS00002JB13
J 0
(-400 50);
DISPLAY 0.510638 (-400 50);
PAINT WHITE (-400 50);
DISPLAY INVISIBLE (-400 50);
FORCEPROP 1 LAST PACK_TYPE 0402LF
J 0
(-100 -200);
DISPLAY 0.510638 (-100 -200);
PAINT SKYBLUE (-100 -200);
DISPLAY INVISIBLE (-100 -200);
FORCEPROP 1 LAST WATTAGE 1/16W
J 2
(-375 -200);
DISPLAY 0.510638 (-375 -200);
PAINT SKYBLUE (-375 -200);
DISPLAY INVISIBLE (-375 -200);
FORCEPROP 1 LAST PATH I51
J 0
(-400 100);
DISPLAY 0.978723 (-400 100);
PAINT WHITE (-400 100);
DISPLAY INVISIBLE (-400 100);
FORCEPROP 2 LAST CDS_LIB pure_quanta
J 0
(-350 -50);
DISPLAY 1.340425 (-350 -50);
DISPLAY INVISIBLE (-350 -50);
FORCEPROP 1 LAST TOLERANCE 5%
J 0
(-350 -150);
DISPLAY 0.510638 (-350 -150);
PAINT SKYBLUE (-350 -150);
DISPLAY INVISIBLE (-350 -150);
FORCEPROP 1 LAST LOCATION R86
J 0
(-400 -25);
DISPLAY 0.702128 (-400 -25);
PAINT YELLOW (-400 -25);
FORCEPROP 1 LASTPIN (-450 -50) $PN 1
J 0
(-438 -38);
DISPLAY 0.808511 (-438 -38);
PAINT WHITE (-438 -38);
FORCEPROP 1 LASTPIN (-250 -50) $PN 2
J 0
(-288 -38);
DISPLAY 0.808511 (-288 -38);
PAINT WHITE (-288 -38);
FORCEPROP 2 LAST $SEC 1
J 0
(-400 200);
DISPLAY 0.680851 (-400 200);
PAINT MONO (-400 200);
DISPLAY INVISIBLE (-400 200);
FORCEPROP 2 LAST CDS_SEC 1
J 0
(-400 200);
DISPLAY 1.021277 (-400 200);
DISPLAY INVISIBLE (-400 200);
FORCEADD UNIVERSAL_POWER..1
(-575 100);
FORCEPROP 3 LASTPIN (-575 50) SIG_NAME P3V3_RGM\g
J 0
(-565 60);
DISPLAY 0.659574 (-565 60);
PAINT MONO (-565 60);
DISPLAY INVISIBLE (-565 60);
FORCEPROP 1 LAST HDL_POWER P3V3_RGM
J 1
(-575 150);
DISPLAY 0.702128 (-575 150);
PAINT GREEN (-575 150);
FORCEPROP 1 LAST PATH I52
J 0
(-525 125);
DISPLAY 0.872340 (-525 125);
PAINT AQUA (-525 125);
DISPLAY INVISIBLE (-525 125);
FORCEPROP 2 LAST CDS_LIB logical_power
J 0
(-575 100);
PAINT MONO (-575 100);
DISPLAY INVISIBLE (-575 100);
FORCEADD UNIVERSAL_GND..1
(575 625);
FORCEPROP 3 LASTPIN (575 675) SIG_NAME GND\g
J 0
(585 685);
DISPLAY 0.659574 (585 685);
PAINT MONO (585 685);
DISPLAY INVISIBLE (585 685);
FORCEPROP 1 LAST PATH I53
J 0
(650 625);
DISPLAY 0.872340 (650 625);
PAINT AQUA (650 625);
DISPLAY INVISIBLE (650 625);
FORCEPROP 1 LAST HDL_POWER GND
J 1
(600 550);
DISPLAY 0.702128 (600 550);
PAINT GREEN (600 550);
DISPLAY INVISIBLE (600 550);
FORCEPROP 2 LAST CDS_LIB logical_power
J 0
(575 625);
DISPLAY INVISIBLE (575 625);
FORCEADD Q_CAP..1
(575 1100);
FORCEPROP 1 LAST VALUE 18PF
J 0
(625 1150);
DISPLAY 0.510638 (625 1150);
PAINT SKYBLUE (625 1150);
FORCEPROP 1 LAST TOLERANCE 5%
J 0
(625 1050);
DISPLAY 0.510638 (625 1050);
PAINT SKYBLUE (625 1050);
FORCEPROP 1 LAST PACK_TYPE 0402
J 0
(625 950);
DISPLAY 0.510638 (625 950);
PAINT SKYBLUE (625 950);
FORCEPROP 1 LAST MATERIAL C0G
J 0
(625 1000);
DISPLAY 0.510638 (625 1000);
PAINT SKYBLUE (625 1000);
FORCEPROP 1 LAST VOLTAGE 50V
J 0
(625 1100);
DISPLAY 0.510638 (625 1100);
PAINT SKYBLUE (625 1100);
FORCEPROP 1 LAST PART_NUMBER CH01806JB07
J 0
(625 950);
DISPLAY 0.510638 (625 950);
PAINT WHITE (625 950);
DISPLAY INVISIBLE (625 950);
FORCEPROP 1 LAST PATH I54
J 0
(625 1250);
DISPLAY 0.978723 (625 1250);
PAINT WHITE (625 1250);
DISPLAY INVISIBLE (625 1250);
FORCEPROP 2 LAST CDS_LIB pure_quanta
J 0
(575 1100);
DISPLAY 1.340425 (575 1100);
DISPLAY INVISIBLE (575 1100);
FORCEPROP 1 LAST LOCATION C209
J 0
(625 1200);
DISPLAY 0.702128 (625 1200);
PAINT YELLOW (625 1200);
FORCEPROP 1 LASTPIN (575 1200) $PN 1
J 0
(585 1180);
DISPLAY 0.808511 (585 1180);
PAINT WHITE (585 1180);
FORCEPROP 1 LASTPIN (575 1000) $PN 2
J 0
(585 980);
DISPLAY 0.808511 (585 980);
PAINT WHITE (585 980);
FORCEPROP 2 LAST $SEC 1
J 0
(625 1350);
DISPLAY 0.680851 (625 1350);
PAINT MONO (625 1350);
DISPLAY INVISIBLE (625 1350);
FORCEPROP 2 LAST CDS_SEC 1
J 0
(625 1350);
DISPLAY 1.021277 (625 1350);
DISPLAY INVISIBLE (625 1350);
FORCEADD MOSFET_NCH_DUAL..1
R 5
(150 -375);
FORCEPROP 1 LAST PART_NUMBER BAM70020047
R 3
J 0
(64 -526);
DISPLAY 0.510638 (64 -526);
PAINT WHITE (64 -526);
FORCEPROP 1 LAST MATERIAL IC
R 3
J 0
(-1 -526);
DISPLAY 0.510638 (-1 -526);
PAINT SKYBLUE (-1 -526);
FORCEPROP 2 LAST VALUE 2N7002KDW
R 3
J 0
(175 -550);
DISPLAY 0.510638 (175 -550);
PAINT SKYBLUE (175 -550);
FORCEPROP 2 LAST PART_TYPE SMLF
R 3
J 0
(225 -550);
DISPLAY 0.510638 (225 -550);
PAINT SKYBLUE (225 -550);
FORCEPROP 1 LAST PATH I56
R 3
J 0
(150 -375);
DISPLAY 0.723404 (150 -375);
PAINT GREEN (150 -375);
DISPLAY INVISIBLE (150 -375);
FORCEPROP 2 LAST CDS_LIB pure_quanta
R 3
J 0
(150 -375);
DISPLAY INVISIBLE (150 -375);
FORCEPROP 1 LAST CDS_LMAN_SYM_OUTLINE -150,150,150,-150
R 3
J 0
(150 -375);
DISPLAY 0.468085 (150 -375);
PAINT GREEN (150 -375);
DISPLAY INVISIBLE (150 -375);
FORCEPROP 1 LAST NEEDS_NO_SIZE TRUE
R 3
J 0
(149 -375);
DISPLAY 0.468085 (149 -375);
PAINT GREEN (149 -375);
DISPLAY INVISIBLE (149 -375);
FORCEPROP 1 LAST LOCATION Q2
R 3
J 0
(124 -526);
DISPLAY 0.702128 (124 -526);
PAINT YELLOW (124 -526);
FORCEPROP 2 LASTPIN (350 -425) $PN 6
J 0
(360 -415);
DISPLAY 0.808511 (360 -415);
PAINT WHITE (360 -415);
FORCEPROP 2 LASTPIN (100 -175) $PN 2
R 1
J 0
(90 -165);
DISPLAY 0.808511 (90 -165);
PAINT WHITE (90 -165);
FORCEPROP 2 LASTPIN (-50 -425) $PN 1
J 2
(-60 -415);
DISPLAY 0.808511 (-60 -415);
PAINT WHITE (-60 -415);
FORCEPROP 2 LAST $SEC 1
J 0
(350 -150);
DISPLAY 0.680851 (350 -150);
PAINT MONO (350 -150);
DISPLAY INVISIBLE (350 -150);
FORCEPROP 2 LAST CDS_SEC 1
J 0
(350 -150);
DISPLAY 0.680851 (350 -150);
DISPLAY INVISIBLE (350 -150);
FORCEADD Q_RES..2
(1450 1075);
FORCEPROP 1 LAST PACK_TYPE 0402LF
J 0
(1500 925);
DISPLAY 0.510638 (1500 925);
PAINT SKYBLUE (1500 925);
FORCEPROP 1 LAST MATERIAL CHIP
J 0
(1500 1025);
DISPLAY 0.510638 (1500 1025);
PAINT SKYBLUE (1500 1025);
FORCEPROP 1 LAST WATTAGE 1/16W
J 0
(1500 1075);
DISPLAY 0.510638 (1500 1075);
PAINT SKYBLUE (1500 1075);
FORCEPROP 1 LAST TOLERANCE 1%
J 0
(1500 1125);
DISPLAY 0.510638 (1500 1125);
PAINT SKYBLUE (1500 1125);
FORCEPROP 1 LAST VALUE 150
J 0
(1500 1175);
DISPLAY 0.510638 (1500 1175);
PAINT SKYBLUE (1500 1175);
FORCEPROP 1 LAST PART_NUMBER CS11502FB07
J 0
(1500 975);
DISPLAY 0.510638 (1500 975);
PAINT WHITE (1500 975);
FORCEPROP 1 LAST PATH I57
J 0
(1500 1250);
DISPLAY 0.978723 (1500 1250);
PAINT WHITE (1500 1250);
DISPLAY INVISIBLE (1500 1250);
FORCEPROP 2 LAST CDS_LIB pure_quanta
J 0
(1450 1075);
DISPLAY INVISIBLE (1450 1075);
FORCEPROP 1 LAST LOCATION R87
J 0
(1500 1225);
DISPLAY 0.702128 (1500 1225);
PAINT YELLOW (1500 1225);
FORCEPROP 1 LASTPIN (1450 1175) $PN 1
J 0
(1455 1137);
DISPLAY 0.808511 (1455 1137);
PAINT WHITE (1455 1137);
FORCEPROP 1 LASTPIN (1450 975) $PN 2
J 0
(1455 985);
DISPLAY 0.808511 (1455 985);
PAINT WHITE (1455 985);
FORCEPROP 2 LAST $SEC 1
J 0
(1500 1300);
DISPLAY 0.680851 (1500 1300);
PAINT MONO (1500 1300);
DISPLAY INVISIBLE (1500 1300);
FORCEPROP 2 LAST CDS_SEC 1
J 0
(1500 1300);
DISPLAY 0.680851 (1500 1300);
DISPLAY INVISIBLE (1500 1300);
FORCEADD UNIVERSAL_GND..1
(2000 675);
FORCEPROP 3 LASTPIN (2000 725) SIG_NAME GND\g
J 0
(2010 735);
DISPLAY 0.659574 (2010 735);
PAINT MONO (2010 735);
DISPLAY INVISIBLE (2010 735);
FORCEPROP 1 LAST PATH I58
J 0
(2075 675);
DISPLAY 0.872340 (2075 675);
PAINT AQUA (2075 675);
DISPLAY INVISIBLE (2075 675);
FORCEPROP 1 LAST HDL_POWER GND
J 1
(2025 600);
DISPLAY 0.702128 (2025 600);
PAINT GREEN (2025 600);
DISPLAY INVISIBLE (2025 600);
FORCEPROP 2 LAST CDS_LIB logical_power
J 0
(2000 675);
DISPLAY INVISIBLE (2000 675);
FORCEADD Q_RES..2
(2000 1100);
FORCEPROP 1 LAST PACK_TYPE 0402LF
J 0
(2050 925);
DISPLAY 0.510638 (2050 925);
PAINT SKYBLUE (2050 925);
FORCEPROP 1 LAST PART_NUMBER CS11502FB07
J 0
(2050 975);
DISPLAY 0.510638 (2050 975);
PAINT WHITE (2050 975);
FORCEPROP 1 LAST MATERIAL CHIP
J 0
(2050 1025);
DISPLAY 0.510638 (2050 1025);
PAINT SKYBLUE (2050 1025);
FORCEPROP 1 LAST VALUE 150
J 0
(2050 1175);
DISPLAY 0.510638 (2050 1175);
PAINT SKYBLUE (2050 1175);
FORCEPROP 1 LAST TOLERANCE 1%
J 0
(2050 1125);
DISPLAY 0.510638 (2050 1125);
PAINT SKYBLUE (2050 1125);
FORCEPROP 1 LAST WATTAGE 1/16W
J 0
(2050 1075);
DISPLAY 0.510638 (2050 1075);
PAINT SKYBLUE (2050 1075);
FORCEPROP 1 LAST PATH I59
J 0
(2050 1275);
DISPLAY 0.978723 (2050 1275);
PAINT WHITE (2050 1275);
DISPLAY INVISIBLE (2050 1275);
FORCEPROP 2 LAST CDS_LIB pure_quanta
J 0
(2000 1100);
DISPLAY INVISIBLE (2000 1100);
FORCEPROP 1 LAST LOCATION R88
J 0
(2050 1225);
DISPLAY 0.702128 (2050 1225);
PAINT YELLOW (2050 1225);
FORCEPROP 1 LASTPIN (2000 1200) $PN 1
J 0
(2005 1162);
DISPLAY 0.808511 (2005 1162);
PAINT WHITE (2005 1162);
FORCEPROP 1 LASTPIN (2000 1000) $PN 2
J 0
(2005 1010);
DISPLAY 0.808511 (2005 1010);
PAINT WHITE (2005 1010);
FORCEPROP 2 LAST $SEC 1
J 0
(2050 1325);
DISPLAY 0.680851 (2050 1325);
PAINT MONO (2050 1325);
DISPLAY INVISIBLE (2050 1325);
FORCEPROP 2 LAST CDS_SEC 1
J 0
(2050 1325);
DISPLAY 0.680851 (2050 1325);
DISPLAY INVISIBLE (2050 1325);
FORCEADD Q_RES..1
(625 2325);
FORCEPROP 1 LAST VALUE 0
J 2
(825 2325);
DISPLAY 0.510638 (825 2325);
PAINT SKYBLUE (825 2325);
FORCEPROP 1 LAST MATERIAL CHIP
J 0
(645 2275);
DISPLAY 0.510638 (645 2275);
PAINT SKYBLUE (645 2275);
FORCEPROP 1 LAST TOLERANCE 5%
J 0
(520 2275);
DISPLAY 0.510638 (520 2275);
PAINT SKYBLUE (520 2275);
FORCEPROP 1 LAST PACK_TYPE 0402LF
J 0
(875 2175);
DISPLAY 0.510638 (875 2175);
PAINT SKYBLUE (875 2175);
DISPLAY INVISIBLE (875 2175);
FORCEPROP 1 LAST WATTAGE 1/16W
J 2
(600 2175);
DISPLAY 0.510638 (600 2175);
PAINT SKYBLUE (600 2175);
DISPLAY INVISIBLE (600 2175);
FORCEPROP 1 LAST PATH I60
J 0
(575 2475);
DISPLAY 0.978723 (575 2475);
PAINT WHITE (575 2475);
DISPLAY INVISIBLE (575 2475);
FORCEPROP 2 LAST CDS_LIB pure_quanta
J 0
(625 2325);
DISPLAY 1.340425 (625 2325);
DISPLAY INVISIBLE (625 2325);
FORCEPROP 1 LAST PART_NUMBER CS00002JB13
J 0
(575 2425);
DISPLAY 0.510638 (575 2425);
PAINT WHITE (575 2425);
DISPLAY INVISIBLE (575 2425);
FORCEPROP 1 LAST LOCATION R85
J 0
(570 2400);
DISPLAY 0.702128 (570 2400);
PAINT YELLOW (570 2400);
FORCEPROP 1 LASTPIN (525 2325) $PN 1
J 0
(537 2337);
DISPLAY 0.808511 (537 2337);
PAINT WHITE (537 2337);
FORCEPROP 1 LASTPIN (725 2325) $PN 2
J 0
(687 2337);
DISPLAY 0.808511 (687 2337);
PAINT WHITE (687 2337);
FORCEPROP 2 LAST $SEC 1
J 0
(620 2560);
DISPLAY 0.680851 (620 2560);
PAINT MONO (620 2560);
DISPLAY INVISIBLE (620 2560);
FORCEPROP 2 LAST CDS_SEC 1
J 0
(620 2560);
DISPLAY 1.021277 (620 2560);
DISPLAY INVISIBLE (620 2560);
FORCEADD Q_RES..1
(425 2725);
FORCEPROP 1 LAST VALUE 0
J 2
(650 2725);
DISPLAY 0.510638 (650 2725);
PAINT SKYBLUE (650 2725);
FORCEPROP 1 LAST TOLERANCE 5%
J 0
(300 2675);
DISPLAY 0.510638 (300 2675);
PAINT SKYBLUE (300 2675);
FORCEPROP 1 LAST MATERIAL CHIP
J 0
(450 2675);
DISPLAY 0.510638 (450 2675);
PAINT SKYBLUE (450 2675);
FORCEPROP 1 LAST PACK_TYPE 0402LF
J 0
(675 2575);
DISPLAY 0.510638 (675 2575);
PAINT SKYBLUE (675 2575);
DISPLAY INVISIBLE (675 2575);
FORCEPROP 1 LAST WATTAGE 1/16W
J 2
(400 2575);
DISPLAY 0.510638 (400 2575);
PAINT SKYBLUE (400 2575);
DISPLAY INVISIBLE (400 2575);
FORCEPROP 1 LAST PATH I61
J 0
(375 2875);
DISPLAY 0.978723 (375 2875);
PAINT WHITE (375 2875);
DISPLAY INVISIBLE (375 2875);
FORCEPROP 2 LAST CDS_LIB pure_quanta
J 0
(425 2725);
DISPLAY 1.340425 (425 2725);
DISPLAY INVISIBLE (425 2725);
FORCEPROP 1 LAST PART_NUMBER CS00002JB13
J 0
(375 2825);
DISPLAY 0.510638 (375 2825);
PAINT WHITE (375 2825);
DISPLAY INVISIBLE (375 2825);
FORCEPROP 1 LAST LOCATION R84
J 0
(375 2775);
DISPLAY 0.702128 (375 2775);
PAINT YELLOW (375 2775);
FORCEPROP 1 LASTPIN (325 2725) $PN 1
J 0
(337 2737);
DISPLAY 0.808511 (337 2737);
PAINT WHITE (337 2737);
FORCEPROP 1 LASTPIN (525 2725) $PN 2
J 0
(487 2737);
DISPLAY 0.808511 (487 2737);
PAINT WHITE (487 2737);
FORCEPROP 2 LAST $SEC 1
J 0
(420 2960);
DISPLAY 0.680851 (420 2960);
PAINT MONO (420 2960);
DISPLAY INVISIBLE (420 2960);
FORCEPROP 2 LAST CDS_SEC 1
J 0
(420 2960);
DISPLAY 1.021277 (420 2960);
DISPLAY INVISIBLE (420 2960);
FORCEADD Q_RES..2
(775 -200);
FORCEPROP 1 LAST WATTAGE 1/16W
J 0
(825 -225);
DISPLAY 0.510638 (825 -225);
PAINT SKYBLUE (825 -225);
FORCEPROP 1 LAST MATERIAL CHIP
J 0
(825 -250);
DISPLAY 0.510638 (825 -250);
PAINT SKYBLUE (825 -250);
FORCEPROP 1 LAST PACK_TYPE 0402LF
J 0
(825 -275);
DISPLAY 0.510638 (825 -275);
PAINT SKYBLUE (825 -275);
FORCEPROP 1 LAST VALUE 2.2K
J 0
(825 -175);
DISPLAY 0.510638 (825 -175);
PAINT SKYBLUE (825 -175);
FORCEPROP 1 LAST TOLERANCE 5%
J 0
(825 -200);
DISPLAY 0.510638 (825 -200);
PAINT SKYBLUE (825 -200);
FORCEPROP 1 LAST PART_NUMBER CS22202JB07
J 0
(815 -50);
DISPLAY 0.510638 (815 -50);
PAINT WHITE (815 -50);
DISPLAY INVISIBLE (815 -50);
FORCEPROP 1 LAST PATH I62
J 0
(825 -25);
DISPLAY 0.978723 (825 -25);
PAINT WHITE (825 -25);
DISPLAY INVISIBLE (825 -25);
FORCEPROP 2 LAST CDS_LIB pure_quanta
J 0
(775 -200);
DISPLAY INVISIBLE (775 -200);
FORCEPROP 1 LAST LOCATION R91
J 0
(825 -150);
DISPLAY 0.702128 (825 -150);
PAINT YELLOW (825 -150);
FORCEPROP 1 LASTPIN (775 -100) $PN 1
J 0
(780 -138);
DISPLAY 0.808511 (780 -138);
PAINT WHITE (780 -138);
FORCEPROP 1 LASTPIN (775 -300) $PN 2
J 0
(780 -290);
DISPLAY 0.808511 (780 -290);
PAINT WHITE (780 -290);
FORCEPROP 2 LAST $SEC 1
J 0
(825 25);
DISPLAY 0.680851 (825 25);
PAINT MONO (825 25);
DISPLAY INVISIBLE (825 25);
FORCEPROP 2 LAST CDS_SEC 1
J 0
(825 25);
DISPLAY 0.680851 (825 25);
DISPLAY INVISIBLE (825 25);
FORCEADD UNIVERSAL_POWER..1
(775 75);
FORCEPROP 3 LASTPIN (775 25) SIG_NAME CRT_VCC5\g
J 0
(785 35);
DISPLAY 0.659574 (785 35);
PAINT MONO (785 35);
DISPLAY INVISIBLE (785 35);
FORCEPROP 1 LAST HDL_POWER CRT_VCC5
J 1
(775 125);
DISPLAY 0.702128 (775 125);
PAINT GREEN (775 125);
FORCEPROP 1 LAST PATH I63
J 0
(825 100);
DISPLAY 0.872340 (825 100);
PAINT AQUA (825 100);
DISPLAY INVISIBLE (825 100);
FORCEPROP 2 LAST CDS_LIB logical_power
J 0
(775 75);
DISPLAY 1.340425 (775 75);
DISPLAY INVISIBLE (775 75);
FORCEADD Q_RES..2
(1025 -200);
FORCEPROP 1 LAST TOLERANCE 5%
J 0
(1075 -200);
DISPLAY 0.510638 (1075 -200);
PAINT SKYBLUE (1075 -200);
FORCEPROP 1 LAST WATTAGE 1/16W
J 0
(1075 -225);
DISPLAY 0.510638 (1075 -225);
PAINT SKYBLUE (1075 -225);
FORCEPROP 1 LAST VALUE 2.2K
J 0
(1075 -175);
DISPLAY 0.510638 (1075 -175);
PAINT SKYBLUE (1075 -175);
FORCEPROP 1 LAST MATERIAL CHIP
J 0
(1075 -250);
DISPLAY 0.510638 (1075 -250);
PAINT SKYBLUE (1075 -250);
FORCEPROP 1 LAST PACK_TYPE 0402LF
J 0
(1075 -275);
DISPLAY 0.510638 (1075 -275);
PAINT SKYBLUE (1075 -275);
FORCEPROP 1 LAST PART_NUMBER CS22202JB07
J 0
(1140 -200);
DISPLAY 0.510638 (1140 -200);
PAINT WHITE (1140 -200);
DISPLAY INVISIBLE (1140 -200);
FORCEPROP 1 LAST PATH I64
J 0
(1075 -25);
DISPLAY 0.978723 (1075 -25);
PAINT WHITE (1075 -25);
DISPLAY INVISIBLE (1075 -25);
FORCEPROP 2 LAST CDS_LIB pure_quanta
J 0
(1025 -200);
DISPLAY INVISIBLE (1025 -200);
FORCEPROP 1 LAST LOCATION R92
J 0
(1075 -150);
DISPLAY 0.702128 (1075 -150);
PAINT YELLOW (1075 -150);
FORCEPROP 1 LASTPIN (1025 -100) $PN 1
J 0
(1030 -138);
DISPLAY 0.808511 (1030 -138);
PAINT WHITE (1030 -138);
FORCEPROP 1 LASTPIN (1025 -300) $PN 2
J 0
(1030 -290);
DISPLAY 0.808511 (1030 -290);
PAINT WHITE (1030 -290);
FORCEPROP 2 LAST $SEC 1
J 0
(1075 25);
DISPLAY 0.680851 (1075 25);
PAINT MONO (1075 25);
DISPLAY INVISIBLE (1075 25);
FORCEPROP 2 LAST CDS_SEC 1
J 0
(1075 25);
DISPLAY 0.680851 (1075 25);
DISPLAY INVISIBLE (1075 25);
FORCEADD Q_RES..2
(2525 1100);
FORCEPROP 1 LAST TOLERANCE 1%
J 0
(2575 1125);
DISPLAY 0.510638 (2575 1125);
PAINT SKYBLUE (2575 1125);
FORCEPROP 1 LAST WATTAGE 1/16W
J 0
(2575 1075);
DISPLAY 0.510638 (2575 1075);
PAINT SKYBLUE (2575 1075);
FORCEPROP 1 LAST MATERIAL CHIP
J 0
(2575 1025);
DISPLAY 0.510638 (2575 1025);
PAINT SKYBLUE (2575 1025);
FORCEPROP 1 LAST PART_NUMBER CS11502FB07
J 0
(2575 975);
DISPLAY 0.510638 (2575 975);
PAINT WHITE (2575 975);
FORCEPROP 1 LAST PACK_TYPE 0402LF
J 0
(2575 925);
DISPLAY 0.510638 (2575 925);
PAINT SKYBLUE (2575 925);
FORCEPROP 1 LAST VALUE 150
J 0
(2575 1175);
DISPLAY 0.510638 (2575 1175);
PAINT SKYBLUE (2575 1175);
FORCEPROP 1 LAST PATH I65
J 0
(2575 1275);
DISPLAY 0.978723 (2575 1275);
PAINT WHITE (2575 1275);
DISPLAY INVISIBLE (2575 1275);
FORCEPROP 2 LAST CDS_LIB pure_quanta
J 0
(2525 1100);
DISPLAY INVISIBLE (2525 1100);
FORCEPROP 1 LAST LOCATION R89
J 0
(2575 1225);
DISPLAY 0.702128 (2575 1225);
PAINT YELLOW (2575 1225);
FORCEPROP 1 LASTPIN (2525 1200) $PN 1
J 0
(2530 1162);
DISPLAY 0.808511 (2530 1162);
PAINT WHITE (2530 1162);
FORCEPROP 1 LASTPIN (2525 1000) $PN 2
J 0
(2530 1010);
DISPLAY 0.808511 (2530 1010);
PAINT WHITE (2530 1010);
FORCEPROP 2 LAST $SEC 1
J 0
(2575 1325);
DISPLAY 0.680851 (2575 1325);
PAINT MONO (2575 1325);
DISPLAY INVISIBLE (2575 1325);
FORCEPROP 2 LAST CDS_SEC 1
J 0
(2575 1325);
DISPLAY 0.680851 (2575 1325);
DISPLAY INVISIBLE (2575 1325);
FORCEADD OFFPAGE..3
(2075 -425);
FORCEPROP 2 LAST $XR0 23 
J 0
(2289 -425);
DISPLAY 0.638298 (2289 -425);
PAINT MONO (2289 -425);
FORCEPROP 2 LAST PATH I66
J 0
(2300 -375);
DISPLAY 1.021277 (2300 -375);
DISPLAY INVISIBLE (2300 -375);
FORCEPROP 1 LAST COMMENT_BODY TRUE
J 0
(2025 -525);
DISPLAY 1.319149 (2025 -525);
PAINT PEACH (2025 -525);
DISPLAY INVISIBLE (2025 -525);
FORCEPROP 1 LAST OFFPAGE TRUE
J 0
(2400 -550);
DISPLAY 1.340425 (2400 -550);
PAINT GREEN (2400 -550);
DISPLAY INVISIBLE (2400 -550);
FORCEPROP 2 LAST ROOM SM_CONTROLLER
J 0
(1800 -375);
DISPLAY 1.319149 (1800 -375);
DISPLAY INVISIBLE (1800 -375);
FORCEPROP 2 LAST CDS_LIB standard
J 0
(2075 -425);
DISPLAY 2.085106 (2075 -425);
DISPLAY INVISIBLE (2075 -425);
FORCEADD Q_CAP..1
(4750 700);
FORCEPROP 1 LAST TOLERANCE 1%
J 0
(4800 650);
DISPLAY 0.510638 (4800 650);
PAINT SKYBLUE (4800 650);
FORCEPROP 1 LAST PACK_TYPE 0402
J 0
(4800 555);
DISPLAY 0.510638 (4800 555);
PAINT SKYBLUE (4800 555);
FORCEPROP 1 LAST VOLTAGE 50V
J 0
(4800 700);
DISPLAY 0.510638 (4800 700);
PAINT SKYBLUE (4800 700);
FORCEPROP 1 LAST VALUE 10PF
J 0
(4800 750);
DISPLAY 0.510638 (4800 750);
PAINT SKYBLUE (4800 750);
FORCEPROP 1 LAST MATERIAL NPO
J 0
(4800 600);
DISPLAY 0.510638 (4800 600);
PAINT SKYBLUE (4800 600);
FORCEPROP 1 LAST PART_NUMBER TMP_QCH0106F0B00
J 0
(4800 550);
DISPLAY 0.510638 (4800 550);
PAINT WHITE (4800 550);
DISPLAY INVISIBLE (4800 550);
FORCEPROP 2 LAST CDS_LIB pure_quanta
J 0
(4750 700);
DISPLAY 1.340425 (4750 700);
DISPLAY INVISIBLE (4750 700);
FORCEPROP 1 LAST PATH I67
J 0
(4800 850);
DISPLAY 0.978723 (4800 850);
PAINT WHITE (4800 850);
DISPLAY INVISIBLE (4800 850);
FORCEPROP 1 LAST LOCATION C211
J 0
(4800 800);
DISPLAY 0.702128 (4800 800);
PAINT YELLOW (4800 800);
FORCEPROP 1 LASTPIN (4750 800) $PN 1
J 0
(4760 780);
DISPLAY 0.808511 (4760 780);
PAINT WHITE (4760 780);
FORCEPROP 1 LASTPIN (4750 600) $PN 2
J 0
(4760 580);
DISPLAY 0.808511 (4760 580);
PAINT WHITE (4760 580);
FORCEPROP 2 LAST $SEC 1
J 0
(4800 955);
DISPLAY 0.680851 (4800 955);
PAINT MONO (4800 955);
DISPLAY INVISIBLE (4800 955);
FORCEPROP 2 LAST CDS_SEC 1
J 0
(4800 955);
DISPLAY 1.021277 (4800 955);
DISPLAY INVISIBLE (4800 955);
FORCEADD Q_RES..1
(4750 3425);
FORCEPROP 1 LAST VALUE 2.21K
J 2
(4975 3425);
DISPLAY 0.510638 (4975 3425);
PAINT SKYBLUE (4975 3425);
FORCEPROP 1 LAST MATERIAL EMPTY
J 0
(4850 3375);
DISPLAY 0.510638 (4850 3375);
PAINT RED (4850 3375);
FORCEPROP 1 LAST TOLERANCE 1%
J 0
(4750 3325);
DISPLAY 0.510638 (4750 3325);
PAINT SKYBLUE (4750 3325);
DISPLAY INVISIBLE (4750 3325);
FORCEPROP 1 LAST PART_NUMBER CS22212FB06
J 0
(4700 3525);
DISPLAY 0.510638 (4700 3525);
PAINT WHITE (4700 3525);
DISPLAY INVISIBLE (4700 3525);
FORCEPROP 1 LAST PACK_TYPE 0402LF
J 0
(5000 3275);
DISPLAY 0.510638 (5000 3275);
PAINT SKYBLUE (5000 3275);
DISPLAY INVISIBLE (5000 3275);
FORCEPROP 1 LAST WATTAGE 1/16W
J 2
(4725 3275);
DISPLAY 0.510638 (4725 3275);
PAINT SKYBLUE (4725 3275);
DISPLAY INVISIBLE (4725 3275);
FORCEPROP 1 LAST PATH I68
J 0
(4700 3575);
DISPLAY 0.978723 (4700 3575);
PAINT WHITE (4700 3575);
DISPLAY INVISIBLE (4700 3575);
FORCEPROP 2 LAST CDS_LIB pure_quanta
J 0
(4750 3425);
DISPLAY 1.340425 (4750 3425);
DISPLAY INVISIBLE (4750 3425);
FORCEPROP 1 LAST LOCATION R17
J 0
(4700 3475);
DISPLAY 0.702128 (4700 3475);
PAINT YELLOW (4700 3475);
FORCEPROP 1 LASTPIN (4650 3425) $PN 1
J 0
(4662 3437);
DISPLAY 0.808511 (4662 3437);
PAINT WHITE (4662 3437);
FORCEPROP 1 LASTPIN (4850 3425) $PN 2
J 0
(4812 3437);
DISPLAY 0.808511 (4812 3437);
PAINT WHITE (4812 3437);
FORCEPROP 2 LAST $SEC 1
J 0
(4725 3650);
DISPLAY 0.680851 (4725 3650);
PAINT MONO (4725 3650);
DISPLAY INVISIBLE (4725 3650);
FORCEPROP 2 LAST CDS_SEC 1
J 0
(4725 3650);
DISPLAY 1.021277 (4725 3650);
DISPLAY INVISIBLE (4725 3650);
FORCEADD UNIVERSAL_POWER..1
(5625 4850);
FORCEPROP 3 LASTPIN (5625 4800) SIG_NAME CRT_VCC5\g
J 0
(5635 4810);
DISPLAY 0.659574 (5635 4810);
PAINT MONO (5635 4810);
DISPLAY INVISIBLE (5635 4810);
FORCEPROP 1 LAST HDL_POWER CRT_VCC5
J 1
(5625 4900);
DISPLAY 0.702128 (5625 4900);
PAINT GREEN (5625 4900);
FORCEPROP 2 LAST CDS_LIB logical_power
J 0
(5625 4850);
DISPLAY INVISIBLE (5625 4850);
FORCEPROP 1 LAST PATH I71
J 0
(5675 4875);
DISPLAY 0.872340 (5675 4875);
PAINT AQUA (5675 4875);
DISPLAY INVISIBLE (5675 4875);
FORCEADD UNIVERSAL_GND..1
(6075 3700);
FORCEPROP 3 LASTPIN (6075 3750) SIG_NAME GND\g
J 0
(6085 3760);
DISPLAY 0.659574 (6085 3760);
PAINT MONO (6085 3760);
DISPLAY INVISIBLE (6085 3760);
FORCEPROP 2 LAST CDS_LIB logical_power
J 0
(6075 3700);
DISPLAY INVISIBLE (6075 3700);
FORCEPROP 1 LAST HDL_POWER GND
J 1
(6100 3625);
DISPLAY 0.702128 (6100 3625);
PAINT GREEN (6100 3625);
DISPLAY INVISIBLE (6100 3625);
FORCEPROP 1 LAST PATH I73
J 0
(6150 3700);
DISPLAY 0.872340 (6150 3700);
PAINT AQUA (6150 3700);
DISPLAY INVISIBLE (6150 3700);
FORCEADD BZA462A..1
R 3
(6200 4200);
FORCEPROP 1 LAST MATERIAL EMPTY
R 1
J 2
(5711 4447);
DISPLAY 0.510638 (5711 4447);
PAINT RED (5711 4447);
FORCEPROP 1 LAST PART_NUMBER BCZA462AZ01
R 1
J 2
(5656 4447);
DISPLAY 0.510638 (5656 4447);
PAINT WHITE (5656 4447);
FORCEPROP 2 LAST VALUE BZA462A
R 1
J 2
(5550 4425);
DISPLAY 0.510638 (5550 4425);
PAINT SKYBLUE (5550 4425);
FORCEPROP 2 LAST PART_TYPE SMLF
R 1
J 2
(5500 4425);
DISPLAY 0.510638 (5500 4425);
PAINT SKYBLUE (5500 4425);
FORCEPROP 1 LAST NEEDS_NO_SIZE TRUE
R 1
J 2
(6200 4200);
DISPLAY 0.723404 (6200 4200);
PAINT GREEN (6200 4200);
DISPLAY INVISIBLE (6200 4200);
FORCEPROP 1 LAST CDS_LMAN_SYM_OUTLINE -250,475,250,-475
R 1
J 2
(6200 4200);
DISPLAY 0.468085 (6200 4200);
PAINT GREEN (6200 4200);
DISPLAY INVISIBLE (6200 4200);
FORCEPROP 2 LAST CDS_LIB pure_quanta
R 1
J 2
(6200 4200);
DISPLAY INVISIBLE (6200 4200);
FORCEPROP 1 LAST PATH I74
R 1
J 2
(6200 4200);
DISPLAY 0.723404 (6200 4200);
PAINT GREEN (6200 4200);
DISPLAY INVISIBLE (6200 4200);
FORCEPROP 1 LAST LOCATION D12
R 1
J 2
(5593 4447);
DISPLAY 0.702128 (5593 4447);
PAINT YELLOW (5593 4447);
FORCEPROP 2 LASTPIN (5825 4600) $PN 1
R 1
J 0
(5815 4610);
DISPLAY 0.808511 (5815 4610);
PAINT WHITE (5815 4610);
FORCEPROP 2 LASTPIN (6075 3800) $PN 2
R 1
J 2
(6065 3790);
DISPLAY 0.808511 (6065 3790);
PAINT WHITE (6065 3790);
FORCEPROP 2 LASTPIN (6075 4600) $PN 3
R 1
J 0
(6065 4610);
DISPLAY 0.808511 (6065 4610);
PAINT WHITE (6065 4610);
FORCEPROP 2 LASTPIN (6325 4600) $PN 4
R 1
J 0
(6315 4610);
DISPLAY 0.808511 (6315 4610);
PAINT WHITE (6315 4610);
FORCEPROP 2 LASTPIN (6325 3800) $PN 5
R 1
J 2
(6315 3790);
DISPLAY 0.808511 (6315 3790);
PAINT WHITE (6315 3790);
FORCEPROP 2 LASTPIN (6575 4600) $PN 6
R 1
J 0
(6565 4610);
DISPLAY 0.808511 (6565 4610);
PAINT WHITE (6565 4610);
FORCEPROP 2 LAST $SEC 1
J 0
(6675 4625);
DISPLAY 0.680851 (6675 4625);
PAINT MONO (6675 4625);
DISPLAY INVISIBLE (6675 4625);
FORCEPROP 2 LAST CDS_SEC 1
J 0
(6675 4625);
DISPLAY 0.680851 (6675 4625);
DISPLAY INVISIBLE (6675 4625);
FORCEADD Q_RES..1
(4875 3575);
FORCEPROP 1 LAST VALUE 2.21K
J 2
(5100 3575);
DISPLAY 0.510638 (5100 3575);
PAINT SKYBLUE (5100 3575);
FORCEPROP 1 LAST MATERIAL EMPTY
J 0
(4975 3500);
DISPLAY 0.510638 (4975 3500);
PAINT RED (4975 3500);
FORCEPROP 2 LAST CDS_LIB pure_quanta
J 0
(4875 3575);
DISPLAY 1.340425 (4875 3575);
DISPLAY INVISIBLE (4875 3575);
FORCEPROP 1 LAST PATH I75
J 0
(4825 3725);
DISPLAY 0.978723 (4825 3725);
PAINT WHITE (4825 3725);
DISPLAY INVISIBLE (4825 3725);
FORCEPROP 1 LAST WATTAGE 1/16W
J 2
(4850 3425);
DISPLAY 0.510638 (4850 3425);
PAINT SKYBLUE (4850 3425);
DISPLAY INVISIBLE (4850 3425);
FORCEPROP 1 LAST PACK_TYPE 0402LF
J 0
(5125 3425);
DISPLAY 0.510638 (5125 3425);
PAINT SKYBLUE (5125 3425);
DISPLAY INVISIBLE (5125 3425);
FORCEPROP 1 LAST PART_NUMBER CS22212FB06
J 0
(4825 3675);
DISPLAY 0.510638 (4825 3675);
PAINT WHITE (4825 3675);
DISPLAY INVISIBLE (4825 3675);
FORCEPROP 1 LAST TOLERANCE 1%
J 0
(4875 3475);
DISPLAY 0.510638 (4875 3475);
PAINT SKYBLUE (4875 3475);
DISPLAY INVISIBLE (4875 3475);
FORCEPROP 1 LAST LOCATION R16
J 0
(4825 3625);
DISPLAY 0.702128 (4825 3625);
PAINT YELLOW (4825 3625);
FORCEPROP 1 LASTPIN (4775 3575) $PN 1
J 0
(4787 3587);
DISPLAY 0.808511 (4787 3587);
PAINT WHITE (4787 3587);
FORCEPROP 1 LASTPIN (4975 3575) $PN 2
J 0
(4937 3587);
DISPLAY 0.808511 (4937 3587);
PAINT WHITE (4937 3587);
FORCEPROP 2 LAST $SEC 1
J 0
(4850 3800);
DISPLAY 0.680851 (4850 3800);
PAINT MONO (4850 3800);
DISPLAY INVISIBLE (4850 3800);
FORCEPROP 2 LAST CDS_SEC 1
J 0
(4850 3800);
DISPLAY 1.021277 (4850 3800);
DISPLAY INVISIBLE (4850 3800);
FORCEADD UNIVERSAL_GND..1
(6325 3700);
FORCEPROP 3 LASTPIN (6325 3750) SIG_NAME GND\g
J 0
(6335 3760);
DISPLAY 0.659574 (6335 3760);
PAINT MONO (6335 3760);
DISPLAY INVISIBLE (6335 3760);
FORCEPROP 2 LAST CDS_LIB logical_power
J 0
(6325 3700);
DISPLAY INVISIBLE (6325 3700);
FORCEPROP 1 LAST PATH I76
J 0
(6400 3700);
DISPLAY 0.872340 (6400 3700);
PAINT AQUA (6400 3700);
DISPLAY INVISIBLE (6400 3700);
FORCEPROP 1 LAST HDL_POWER GND
J 1
(6350 3625);
DISPLAY 0.702128 (6350 3625);
PAINT GREEN (6350 3625);
DISPLAY INVISIBLE (6350 3625);
FORCEADD Q_CAP..1
(5200 700);
FORCEPROP 1 LAST TOLERANCE 1%
J 0
(5250 650);
DISPLAY 0.510638 (5250 650);
PAINT SKYBLUE (5250 650);
FORCEPROP 1 LAST VOLTAGE 50V
J 0
(5250 700);
DISPLAY 0.510638 (5250 700);
PAINT SKYBLUE (5250 700);
FORCEPROP 1 LAST VALUE 10PF
J 0
(5250 750);
DISPLAY 0.510638 (5250 750);
PAINT SKYBLUE (5250 750);
FORCEPROP 1 LAST PACK_TYPE 0402
J 0
(5250 550);
DISPLAY 0.510638 (5250 550);
PAINT SKYBLUE (5250 550);
FORCEPROP 1 LAST MATERIAL NPO
J 0
(5250 600);
DISPLAY 0.510638 (5250 600);
PAINT SKYBLUE (5250 600);
FORCEPROP 1 LAST PART_NUMBER TMP_QCH0106F0B00
J 0
(5250 550);
DISPLAY 0.510638 (5250 550);
PAINT WHITE (5250 550);
DISPLAY INVISIBLE (5250 550);
FORCEPROP 2 LAST CDS_LIB pure_quanta
J 0
(5200 700);
DISPLAY 1.340425 (5200 700);
DISPLAY INVISIBLE (5200 700);
FORCEPROP 1 LAST PATH I77
J 0
(5250 850);
DISPLAY 0.978723 (5250 850);
PAINT WHITE (5250 850);
DISPLAY INVISIBLE (5250 850);
FORCEPROP 1 LAST LOCATION C212
J 0
(5250 800);
DISPLAY 0.702128 (5250 800);
PAINT YELLOW (5250 800);
FORCEPROP 1 LASTPIN (5200 800) $PN 1
J 0
(5210 780);
DISPLAY 0.808511 (5210 780);
PAINT WHITE (5210 780);
FORCEPROP 1 LASTPIN (5200 600) $PN 2
J 0
(5210 580);
DISPLAY 0.808511 (5210 580);
PAINT WHITE (5210 580);
FORCEPROP 2 LAST $SEC 1
J 0
(5250 950);
DISPLAY 0.680851 (5250 950);
PAINT MONO (5250 950);
DISPLAY INVISIBLE (5250 950);
FORCEPROP 2 LAST CDS_SEC 1
J 0
(5250 950);
DISPLAY 1.021277 (5250 950);
DISPLAY INVISIBLE (5250 950);
FORCEADD UNIVERSAL_GND..1
(6000 250);
FORCEPROP 3 LASTPIN (6000 300) SIG_NAME GND\g
J 0
(6010 310);
DISPLAY 0.659574 (6010 310);
PAINT MONO (6010 310);
DISPLAY INVISIBLE (6010 310);
FORCEPROP 2 LAST CDS_LIB logical_power
J 0
(6000 250);
DISPLAY INVISIBLE (6000 250);
FORCEPROP 1 LAST HDL_POWER GND
J 1
(6025 175);
DISPLAY 0.702128 (6025 175);
PAINT GREEN (6025 175);
DISPLAY INVISIBLE (6025 175);
FORCEPROP 1 LAST PATH I82
J 0
(6075 250);
DISPLAY 0.872340 (6075 250);
PAINT AQUA (6075 250);
DISPLAY INVISIBLE (6075 250);
FORCEADD Q_CAP..1
(5600 700);
FORCEPROP 1 LAST MATERIAL EMPTY
J 0
(5650 600);
DISPLAY 0.510638 (5650 600);
PAINT RED (5650 600);
FORCEPROP 1 LAST PACK_TYPE 0402
J 0
(5650 550);
DISPLAY 0.510638 (5650 550);
PAINT SKYBLUE (5650 550);
FORCEPROP 1 LAST TOLERANCE 5%
J 0
(5650 650);
DISPLAY 0.510638 (5650 650);
PAINT SKYBLUE (5650 650);
FORCEPROP 1 LAST VALUE 100PF
J 0
(5650 750);
DISPLAY 0.510638 (5650 750);
PAINT SKYBLUE (5650 750);
FORCEPROP 1 LAST VOLTAGE 50V
J 0
(5650 700);
DISPLAY 0.510638 (5650 700);
PAINT SKYBLUE (5650 700);
FORCEPROP 2 LAST CDS_LIB pure_quanta
J 0
(5600 700);
DISPLAY 1.340425 (5600 700);
DISPLAY INVISIBLE (5600 700);
FORCEPROP 1 LAST PART_NUMBER CH11006JB18
J 0
(5650 550);
DISPLAY 0.510638 (5650 550);
PAINT WHITE (5650 550);
DISPLAY INVISIBLE (5650 550);
FORCEPROP 1 LAST PATH I83
J 0
(5650 850);
DISPLAY 0.978723 (5650 850);
PAINT WHITE (5650 850);
DISPLAY INVISIBLE (5650 850);
FORCEPROP 1 LAST LOCATION C213
J 0
(5650 800);
DISPLAY 0.702128 (5650 800);
PAINT YELLOW (5650 800);
FORCEPROP 1 LASTPIN (5600 800) $PN 1
J 0
(5610 780);
DISPLAY 0.808511 (5610 780);
PAINT WHITE (5610 780);
FORCEPROP 1 LASTPIN (5600 600) $PN 2
J 0
(5610 580);
DISPLAY 0.808511 (5610 580);
PAINT WHITE (5610 580);
FORCEPROP 2 LAST $SEC 1
J 0
(5650 950);
DISPLAY 0.680851 (5650 950);
PAINT MONO (5650 950);
DISPLAY INVISIBLE (5650 950);
FORCEPROP 2 LAST CDS_SEC 1
J 0
(5650 950);
DISPLAY 1.021277 (5650 950);
DISPLAY INVISIBLE (5650 950);
FORCEADD Q_CAP..1
(6000 700);
FORCEPROP 1 LAST PACK_TYPE 0402
J 0
(6050 550);
DISPLAY 0.510638 (6050 550);
PAINT SKYBLUE (6050 550);
FORCEPROP 1 LAST MATERIAL EMPTY
J 0
(6050 600);
DISPLAY 0.510638 (6050 600);
PAINT RED (6050 600);
FORCEPROP 1 LAST TOLERANCE 5%
J 0
(6050 650);
DISPLAY 0.510638 (6050 650);
PAINT SKYBLUE (6050 650);
FORCEPROP 1 LAST VOLTAGE 50V
J 0
(6050 700);
DISPLAY 0.510638 (6050 700);
PAINT SKYBLUE (6050 700);
FORCEPROP 1 LAST VALUE 100PF
J 0
(6050 750);
DISPLAY 0.510638 (6050 750);
PAINT SKYBLUE (6050 750);
FORCEPROP 2 LAST CDS_LIB pure_quanta
J 0
(6000 700);
DISPLAY 1.340425 (6000 700);
DISPLAY INVISIBLE (6000 700);
FORCEPROP 1 LAST PART_NUMBER CH11006JB18
J 0
(6050 550);
DISPLAY 0.510638 (6050 550);
PAINT WHITE (6050 550);
DISPLAY INVISIBLE (6050 550);
FORCEPROP 1 LAST PATH I84
J 0
(6050 850);
DISPLAY 0.978723 (6050 850);
PAINT WHITE (6050 850);
DISPLAY INVISIBLE (6050 850);
FORCEPROP 1 LAST LOCATION C214
J 0
(6050 800);
DISPLAY 0.702128 (6050 800);
PAINT YELLOW (6050 800);
FORCEPROP 1 LASTPIN (6000 800) $PN 1
J 0
(6010 780);
DISPLAY 0.808511 (6010 780);
PAINT WHITE (6010 780);
FORCEPROP 1 LASTPIN (6000 600) $PN 2
J 0
(6010 580);
DISPLAY 0.808511 (6010 580);
PAINT WHITE (6010 580);
FORCEPROP 2 LAST $SEC 1
J 0
(6050 950);
DISPLAY 0.680851 (6050 950);
PAINT MONO (6050 950);
DISPLAY INVISIBLE (6050 950);
FORCEPROP 2 LAST CDS_SEC 1
J 0
(6050 950);
DISPLAY 1.021277 (6050 950);
DISPLAY INVISIBLE (6050 950);
FORCEADD OFFPAGE..2
(5825 1400);
FORCEPROP 2 LAST $XR0 23 
J 0
(6014 1400);
DISPLAY 0.638298 (6014 1400);
PAINT MONO (6014 1400);
FORCEPROP 2 LAST CDS_LIB standard
J 1
(5825 1400);
DISPLAY 1.340425 (5825 1400);
DISPLAY INVISIBLE (5825 1400);
FORCEPROP 1 LAST OFFPAGE TRUE
J 0
(6150 1275);
DISPLAY 1.574468 (6150 1275);
PAINT GREEN (6150 1275);
DISPLAY INVISIBLE (6150 1275);
FORCEPROP 1 LAST COMMENT_BODY TRUE
J 0
(5780 1305);
DISPLAY 1.574468 (5780 1305);
PAINT PEACH (5780 1305);
DISPLAY INVISIBLE (5780 1305);
FORCEPROP 2 LAST PATH I88
J 0
(6025 1450);
DISPLAY 1.021277 (6025 1450);
DISPLAY INVISIBLE (6025 1450);
FORCEADD OFFPAGE..2
(5825 1700);
FORCEPROP 2 LAST $XR0 23 
J 0
(6014 1700);
DISPLAY 0.638298 (6014 1700);
PAINT MONO (6014 1700);
FORCEPROP 2 LAST CDS_LIB standard
J 1
(5825 1700);
DISPLAY 1.340425 (5825 1700);
DISPLAY INVISIBLE (5825 1700);
FORCEPROP 1 LAST OFFPAGE TRUE
J 0
(6150 1575);
DISPLAY 1.574468 (6150 1575);
PAINT GREEN (6150 1575);
DISPLAY INVISIBLE (6150 1575);
FORCEPROP 1 LAST COMMENT_BODY TRUE
J 0
(5780 1605);
DISPLAY 1.574468 (5780 1605);
PAINT PEACH (5780 1605);
DISPLAY INVISIBLE (5780 1605);
FORCEPROP 2 LAST PATH I89
J 0
(6025 1750);
DISPLAY 1.021277 (6025 1750);
DISPLAY INVISIBLE (6025 1750);
FORCEADD OFFPAGE..2
(5825 2000);
FORCEPROP 2 LAST $XR0 23 
J 0
(6014 2000);
DISPLAY 0.638298 (6014 2000);
PAINT MONO (6014 2000);
FORCEPROP 2 LAST CDS_LIB standard
J 1
(5825 2000);
DISPLAY 1.340425 (5825 2000);
DISPLAY INVISIBLE (5825 2000);
FORCEPROP 1 LAST OFFPAGE TRUE
J 0
(6150 1875);
DISPLAY 1.574468 (6150 1875);
PAINT GREEN (6150 1875);
DISPLAY INVISIBLE (6150 1875);
FORCEPROP 1 LAST COMMENT_BODY TRUE
J 0
(5780 1905);
DISPLAY 1.574468 (5780 1905);
PAINT PEACH (5780 1905);
DISPLAY INVISIBLE (5780 1905);
FORCEPROP 2 LAST PATH I90
J 0
(6025 2050);
DISPLAY 1.021277 (6025 2050);
DISPLAY INVISIBLE (6025 2050);
FORCEADD OFFPAGE..2
(5825 2325);
FORCEPROP 2 LAST $XR0 23 
J 0
(6014 2325);
DISPLAY 0.638298 (6014 2325);
PAINT MONO (6014 2325);
FORCEPROP 2 LAST CDS_LIB standard
J 0
(5825 2325);
DISPLAY INVISIBLE (5825 2325);
FORCEPROP 1 LAST OFFPAGE TRUE
J 0
(6150 2200);
DISPLAY 1.574468 (6150 2200);
PAINT GREEN (6150 2200);
DISPLAY INVISIBLE (6150 2200);
FORCEPROP 1 LAST COMMENT_BODY TRUE
J 0
(5780 2230);
DISPLAY 1.574468 (5780 2230);
PAINT PEACH (5780 2230);
DISPLAY INVISIBLE (5780 2230);
FORCEPROP 2 LAST PATH I91
J 0
(6025 2375);
DISPLAY 1.021277 (6025 2375);
DISPLAY INVISIBLE (6025 2375);
FORCEADD OFFPAGE..2
(5825 2725);
FORCEPROP 2 LAST $XR0 23 
J 0
(6014 2725);
DISPLAY 0.638298 (6014 2725);
PAINT MONO (6014 2725);
FORCEPROP 2 LAST CDS_LIB standard
J 0
(5825 2725);
DISPLAY INVISIBLE (5825 2725);
FORCEPROP 1 LAST OFFPAGE TRUE
J 0
(6150 2600);
DISPLAY 1.574468 (6150 2600);
PAINT GREEN (6150 2600);
DISPLAY INVISIBLE (6150 2600);
FORCEPROP 1 LAST COMMENT_BODY TRUE
J 0
(5780 2630);
DISPLAY 1.574468 (5780 2630);
PAINT PEACH (5780 2630);
DISPLAY INVISIBLE (5780 2630);
FORCEPROP 2 LAST PATH I92
J 0
(6025 2775);
DISPLAY 1.021277 (6025 2775);
DISPLAY INVISIBLE (6025 2775);
FORCEADD OFFPAGE..3
(5800 3100);
FORCEPROP 2 LAST $XR0 23 
J 0
(6014 3100);
DISPLAY 0.638298 (6014 3100);
PAINT MONO (6014 3100);
FORCEPROP 2 LAST CDS_LIB standard
J 1
(5800 3100);
DISPLAY 1.340425 (5800 3100);
DISPLAY INVISIBLE (5800 3100);
FORCEPROP 1 LAST OFFPAGE TRUE
J 0
(6125 2975);
DISPLAY 1.574468 (6125 2975);
PAINT GREEN (6125 2975);
DISPLAY INVISIBLE (6125 2975);
FORCEPROP 1 LAST COMMENT_BODY TRUE
J 0
(5750 3000);
DISPLAY 1.574468 (5750 3000);
PAINT PEACH (5750 3000);
DISPLAY INVISIBLE (5750 3000);
FORCEPROP 2 LAST PATH I93
J 0
(6025 3150);
DISPLAY 1.021277 (6025 3150);
DISPLAY INVISIBLE (6025 3150);
FORCEADD OFFPAGE..2
(5825 3300);
FORCEPROP 2 LAST $XR0 23 
J 0
(6014 3300);
DISPLAY 0.638298 (6014 3300);
PAINT MONO (6014 3300);
FORCEPROP 2 LAST PATH I94
J 0
(6025 3350);
DISPLAY 1.021277 (6025 3350);
DISPLAY INVISIBLE (6025 3350);
FORCEPROP 1 LAST COMMENT_BODY TRUE
J 0
(5780 3205);
DISPLAY 1.574468 (5780 3205);
PAINT PEACH (5780 3205);
DISPLAY INVISIBLE (5780 3205);
FORCEPROP 1 LAST OFFPAGE TRUE
J 0
(6150 3175);
DISPLAY 1.574468 (6150 3175);
PAINT GREEN (6150 3175);
DISPLAY INVISIBLE (6150 3175);
FORCEPROP 2 LAST CDS_LIB standard
J 1
(5825 3300);
DISPLAY 1.340425 (5825 3300);
DISPLAY INVISIBLE (5825 3300);
FORCEADD UNIVERSAL_POWER..1
(5350 3775);
FORCEPROP 3 LASTPIN (5350 3725) SIG_NAME CRT_VCC5\g
J 0
(5360 3735);
DISPLAY 0.659574 (5360 3735);
PAINT MONO (5360 3735);
DISPLAY INVISIBLE (5360 3735);
FORCEPROP 1 LAST HDL_POWER CRT_VCC5
J 1
(5350 3825);
DISPLAY 0.702128 (5350 3825);
PAINT GREEN (5350 3825);
FORCEPROP 2 LAST CDS_LIB logical_power
J 0
(5350 3775);
DISPLAY 1.340425 (5350 3775);
DISPLAY INVISIBLE (5350 3775);
FORCEPROP 1 LAST PATH I97
J 0
(5400 3800);
DISPLAY 0.872340 (5400 3800);
PAINT AQUA (5400 3800);
DISPLAY INVISIBLE (5400 3800);
FORCEADD UNIVERSAL_POWER..1
(-2175 4825);
FORCEPROP 3 LASTPIN (-2175 4775) SIG_NAME P5V_AUX\g
J 0
(-2165 4785);
DISPLAY 0.659574 (-2165 4785);
PAINT MONO (-2165 4785);
DISPLAY INVISIBLE (-2165 4785);
FORCEPROP 1 LAST HDL_POWER P5V_AUX
J 1
(-2175 4875);
DISPLAY 0.702128 (-2175 4875);
PAINT GREEN (-2175 4875);
FORCEPROP 1 LAST PATH I98
J 0
(-2125 4850);
DISPLAY 0.872340 (-2125 4850);
PAINT AQUA (-2125 4850);
DISPLAY INVISIBLE (-2125 4850);
FORCEPROP 2 LAST CDS_LIB logical_power
J 0
(-2175 4825);
DISPLAY INVISIBLE (-2175 4825);
FORCEADD Q_RES..1
(-925 3300);
FORCEPROP 1 LAST MATERIAL CHIP
J 0
(-825 3275);
DISPLAY 0.510638 (-825 3275);
PAINT SKYBLUE (-825 3275);
FORCEPROP 1 LAST VALUE 33.2
J 2
(-725 3300);
DISPLAY 0.510638 (-725 3300);
PAINT SKYBLUE (-725 3300);
FORCEPROP 1 LAST TOLERANCE 1%
J 0
(-925 3200);
DISPLAY 0.510638 (-925 3200);
PAINT SKYBLUE (-925 3200);
DISPLAY INVISIBLE (-925 3200);
FORCEPROP 1 LAST PART_NUMBER CS03322FB03
J 0
(-975 3400);
DISPLAY 0.510638 (-975 3400);
PAINT WHITE (-975 3400);
DISPLAY INVISIBLE (-975 3400);
FORCEPROP 1 LAST PACK_TYPE 0402LF
J 0
(-675 3150);
DISPLAY 0.510638 (-675 3150);
PAINT SKYBLUE (-675 3150);
DISPLAY INVISIBLE (-675 3150);
FORCEPROP 1 LAST WATTAGE 1/16W
J 2
(-950 3150);
DISPLAY 0.510638 (-950 3150);
PAINT SKYBLUE (-950 3150);
DISPLAY INVISIBLE (-950 3150);
FORCEPROP 1 LAST PATH I99
J 0
(-975 3450);
DISPLAY 0.978723 (-975 3450);
PAINT WHITE (-975 3450);
DISPLAY INVISIBLE (-975 3450);
FORCEPROP 2 LAST CDS_LIB pure_quanta
J 0
(-925 3300);
DISPLAY 1.340425 (-925 3300);
DISPLAY INVISIBLE (-925 3300);
FORCEPROP 1 LAST LOCATION R28
J 0
(-980 3335);
DISPLAY 0.702128 (-980 3335);
PAINT YELLOW (-980 3335);
FORCEPROP 1 LASTPIN (-1025 3300) $PN 1
J 0
(-1013 3312);
DISPLAY 0.808511 (-1013 3312);
PAINT WHITE (-1013 3312);
FORCEPROP 1 LASTPIN (-825 3300) $PN 2
J 0
(-863 3312);
DISPLAY 0.808511 (-863 3312);
PAINT WHITE (-863 3312);
FORCEPROP 2 LAST $SEC 1
J 0
(-975 3550);
DISPLAY 0.680851 (-975 3550);
PAINT MONO (-975 3550);
DISPLAY INVISIBLE (-975 3550);
FORCEPROP 2 LAST CDS_SEC 1
J 0
(-975 3550);
DISPLAY 1.021277 (-975 3550);
DISPLAY INVISIBLE (-975 3550);
FORCEADD QUANTA_TITLE_BLOCK_C..1
(6875 -1550);
FORCEPROP 0 LAST CDS_CON_LAST_MODIFIED Fri Aug 25 17:25:40 2023
J 0
(4990 -1535);
DISPLAY INVISIBLE (4990 -1535);
FORCEPROP 2 LAST Q_DEPT 
J 1
(3112 -1501);
DISPLAY 1.957447 (3112 -1501);
PAINT GREEN (3112 -1501);
FORCEPROP 1 LAST CUSTOM_TXT_CDS <CON_LAST_MODIFIED>
J 0
(4990 -1535);
DISPLAY 0.978723 (4990 -1535);
FORCEPROP 2 LAST CUSTOM_TXT_CDS <XR_PAGE_TITLE>
J 0
(-1015 3700);
DISPLAY 0.638298 (-1015 3700);
PAINT PINK (-1015 3700);
DISPLAY INVISIBLE (-1015 3700);
FORCEPROP 1 LAST CUSTOM_TXT_CDS <NAME_2>
J 0
(3700 -1500);
FORCEPROP 1 LAST CUSTOM_TXT_CDS <NAME_1>
J 0
(3700 -1375);
FORCEPROP 1 LAST CUSTOM_TXT_CDS <Q_NUMBER>
J 0
(5472 -1447);
DISPLAY 1.212766 (5472 -1447);
FORCEPROP 1 LAST CUSTOM_TXT_CDS <Q_PROJ>
J 0
(4493 -1448);
DISPLAY 1.212766 (4493 -1448);
FORCEPROP 1 LAST CUSTOM_TXT_CDS <Q_REV>
J 0
(6691 -1447);
DISPLAY 1.212766 (6691 -1447);
FORCEPROP 1 LAST CUSTOM_TXT_CDS <CON_PAGE_NUM> OF <CON_TOTAL_PAGES>
J 0
(6429 -1532);
DISPLAY 0.978723 (6429 -1532);
FORCEPROP 1 LAST Q_TITLE BMC VIDEO(FRONT VGA)
J 0
(-2391 -1449);
DISPLAY 2.446809 (-2391 -1449);
PAINT GREEN (-2391 -1449);
FORCEPROP 2 LAST CDS_XR_PAGE_TITLE CR-23 : @SCM_LIB.SCM(SCH_1):PAGE23
J 0
(-1015 3700);
DISPLAY 0.638298 (-1015 3700);
PAINT PINK (-1015 3700);
DISPLAY INVISIBLE (-1015 3700);
FORCEPROP 1 LAST COMMENT_BODY TRUE
J 0
(6887 -1563);
DISPLAY 0.978723 (6887 -1563);
PAINT PEACH (6887 -1563);
DISPLAY INVISIBLE (6887 -1563);
FORCEPROP 2 LAST CDS_LIB pure_quanta
J 0
(6875 -1550);
DISPLAY INVISIBLE (6875 -1550);
FORCEPROP 1 LAST CDS_LMAN_SYM_OUTLINE -9475,6775,100,-125
J 0
(6875 -1550);
DISPLAY 0.468085 (6875 -1550);
PAINT GREEN (6875 -1550);
DISPLAY INVISIBLE (6875 -1550);
FORCEPROP 2 LAST PAGE_BORDER TRUE
J 0
(-1015 3700);
DISPLAY 0.638298 (-1015 3700);
PAINT PINK (-1015 3700);
DISPLAY INVISIBLE (-1015 3700);
FORCEADD DNS..2
(4725 3450);
PAINT RED (4725 3450);
FORCEPROP 1 LAST COMMENT_BODY TRUE
J 0
(4725 3450);
PAINT PEACH (4725 3450);
DISPLAY INVISIBLE (4725 3450);
FORCEPROP 2 LAST CDS_LIB mstr_misc
J 0
(4725 3450);
DISPLAY INVISIBLE (4725 3450);
FORCEPROP 2 LAST ROOM SM_MEM
J 0
(4545 3580);
DISPLAY INVISIBLE (4545 3580);
FORCEADD DNS..2
(5625 700);
PAINT RED (5625 700);
FORCEPROP 2 LAST ROOM SM_MEM
J 0
(5445 830);
DISPLAY INVISIBLE (5445 830);
FORCEPROP 2 LAST CDS_LIB mstr_misc
J 0
(5625 700);
DISPLAY INVISIBLE (5625 700);
FORCEPROP 1 LAST COMMENT_BODY TRUE
J 0
(5625 700);
PAINT PEACH (5625 700);
DISPLAY INVISIBLE (5625 700);
FORCEADD DNS..2
(6025 700);
PAINT RED (6025 700);
FORCEPROP 2 LAST ROOM SM_MEM
J 0
(5845 830);
DISPLAY INVISIBLE (5845 830);
FORCEPROP 2 LAST CDS_LIB mstr_misc
J 0
(6025 700);
DISPLAY INVISIBLE (6025 700);
FORCEPROP 1 LAST COMMENT_BODY TRUE
J 0
(6025 700);
PAINT PEACH (6025 700);
DISPLAY INVISIBLE (6025 700);
FORCEADD DNS..2
(-1825 4675);
PAINT RED (-1825 4675);
FORCEPROP 1 LAST COMMENT_BODY TRUE
R 1
J 0
(-1750 4450);
DISPLAY 0.872340 (-1750 4450);
PAINT PEACH (-1750 4450);
DISPLAY INVISIBLE (-1750 4450);
FORCEPROP 2 LAST CDS_LIB mstr_misc
J 0
(-1825 4675);
DISPLAY INVISIBLE (-1825 4675);
FORCEADD DNS..2
(-1850 4075);
PAINT RED (-1850 4075);
FORCEPROP 1 LAST COMMENT_BODY TRUE
J 0
(-1850 4075);
PAINT PEACH (-1850 4075);
DISPLAY INVISIBLE (-1850 4075);
FORCEPROP 2 LAST ROOM SM_MEM
J 0
(-2030 4205);
DISPLAY INVISIBLE (-2030 4205);
FORCEPROP 2 LAST CDS_LIB mstr_misc
J 0
(-1850 4075);
DISPLAY INVISIBLE (-1850 4075);
FORCEADD DNS..2
(-1400 3875);
PAINT RED (-1400 3875);
FORCEPROP 1 LAST COMMENT_BODY TRUE
R 1
J 0
(-1325 3650);
DISPLAY 0.872340 (-1325 3650);
PAINT PEACH (-1325 3650);
DISPLAY INVISIBLE (-1325 3650);
FORCEPROP 2 LAST CDS_LIB mstr_misc
J 0
(-1400 3875);
PAINT MONO (-1400 3875);
DISPLAY INVISIBLE (-1400 3875);
FORCEADD DNS..2
(4375 -775);
PAINT RED (4375 -775);
FORCEPROP 1 LAST COMMENT_BODY TRUE
R 1
J 0
(4450 -1000);
DISPLAY 0.872340 (4450 -1000);
PAINT PEACH (4450 -1000);
DISPLAY INVISIBLE (4450 -1000);
FORCEPROP 2 LAST CDS_LIB mstr_misc
J 0
(4375 -775);
DISPLAY INVISIBLE (4375 -775);
FORCEADD DNS..2
(3400 -775);
PAINT RED (3400 -775);
FORCEPROP 1 LAST COMMENT_BODY TRUE
R 1
J 0
(3475 -1000);
DISPLAY 0.872340 (3475 -1000);
PAINT PEACH (3475 -1000);
DISPLAY INVISIBLE (3475 -1000);
FORCEPROP 2 LAST CDS_LIB mstr_misc
J 0
(3400 -775);
DISPLAY INVISIBLE (3400 -775);
FORCEADD DNS..2
(4850 3575);
PAINT RED (4850 3575);
FORCEPROP 1 LAST COMMENT_BODY TRUE
J 0
(4850 3575);
PAINT PEACH (4850 3575);
DISPLAY INVISIBLE (4850 3575);
FORCEPROP 2 LAST ROOM SM_MEM
J 0
(4670 3705);
DISPLAY INVISIBLE (4670 3705);
FORCEPROP 2 LAST CDS_LIB mstr_misc
J 0
(4850 3575);
DISPLAY INVISIBLE (4850 3575);
FORCEADD DNS..2
(6200 4275);
PAINT RED (6200 4275);
FORCEPROP 2 LAST ROOM SM_MEM
J 0
(6020 4405);
DISPLAY INVISIBLE (6020 4405);
FORCEPROP 2 LAST CDS_LIB mstr_misc
J 0
(6200 4275);
DISPLAY INVISIBLE (6200 4275);
FORCEPROP 1 LAST COMMENT_BODY TRUE
J 0
(6200 4275);
PAINT PEACH (6200 4275);
DISPLAY INVISIBLE (6200 4275);
WIRE 16 -1 (775 -50)(775 25);
WIRE 16 -1 (1025 -50)(775 -50);
WIRE 16 -1 (775 -50)(775 -100);
WIRE 16 -1 (-1100 100)(-1100 0);
WIRE 16 -1 (-575 50)(-575 -50);
WIRE 16 -1 (5625 4800)(5625 4675);
WIRE 16 -1 (-2175 4775)(-2175 4675);
WIRE 16 -1 (-2100 850)(-2100 750);
WIRE 16 -1 (-1925 2896)(-1925 2825);
WIRE 16 -1 (-1425 4775)(-1425 4675);
WIRE 16 -1 (3050 -775)(3050 -525);
WIRE 16 -1 (3050 -775)(3300 -775);
WIRE 16 -1 (-450 3575)(-450 3650);
WIRE 16 -1 (5350 3725)(5350 3575);
WIRE 16 -1 (3800 4150)(3800 4050);
WIRE 16 -1 (3700 4150)(3800 4150);
WIRE 16 -1 (3800 4300)(3800 4150);
WIRE 16 -1 (2050 4150)(2050 4050);
WIRE 16 -1 (2050 4300)(2050 4150);
WIRE 16 -1 (1950 4150)(2050 4150);
WIRE 16 -1 (6325 3800)(6325 3750);
WIRE 16 -1 (6075 3800)(6075 3750);
WIRE 16 -1 (6000 400)(6000 300);
WIRE 16 -1 (6000 600)(6000 400);
WIRE 16 -1 (5600 400)(6000 400);
WIRE 16 -1 (-2100 325)(-2100 450);
WIRE 16 -1 (-775 750)(-775 700);
WIRE 16 -1 (-775 750)(-425 750);
WIRE 16 -1 (-775 975)(-775 750);
WIRE 16 -1 (-1150 750)(-775 750);
WIRE 16 -1 (-1475 2150)(-1475 2225);
WIRE 16 -1 (-1425 3775)(-1425 3675);
WIRE 16 -1 (575 750)(575 675);
WIRE 16 -1 (575 750)(175 750);
WIRE 16 -1 (975 750)(575 750);
WIRE 16 -1 (575 1000)(575 750);
WIRE 16 -1 (2000 800)(2000 725);
WIRE 16 -1 (1450 800)(2000 800);
WIRE 16 -1 (2525 800)(2000 800);
WIRE 16 -1 (2000 1000)(2000 800);
WIRE 16 -1 (5950 -975)(5950 -925);
WIRE 16 3135 (275 2600)(275 2900);
WIRE 16 3135 (275 2600)(600 2600);
WIRE 16 3135 (600 2900)(275 2900);
WIRE 16 3135 (600 2900)(600 2600);
WIRE 16 3135 (775 2500)(450 2500);
WIRE 16 3135 (775 2500)(775 2200);
WIRE 16 3135 (450 2200)(450 2500);
WIRE 16 3135 (450 2200)(775 2200);
WIRE 16 -1 (-775 2725)(325 2725);
FORCEPROP 0 LAST SIG_NAME V_VGAVS_BUF_R
J 2
(190 2735);
DISPLAY 0.808511 (190 2735);
WIRE 16 -1 (-450 3000)(-450 3375);
WIRE 16 -1 (-1025 3000)(-1025 2975);
WIRE 16 -1 (-625 2575)(-625 3000);
FORCEPROP 0 LAST SIG_NAME BMC_DDC_BUF_EN
J 0
(-1010 3010);
DISPLAY 0.808511 (-1010 3010);
WIRE 16 -1 (-625 3000)(-450 3000);
WIRE 16 -1 (-625 3000)(-1025 3000);
WIRE 16 -1 (-1900 3300)(-1025 3300);
FORCEPROP 2 LAST SIG_NAME V_BMC_LS_DDC_SCL
J 0
(-1835 3310);
DISPLAY 0.808511 (-1835 3310);
WIRE 16 -1 (5600 800)(5600 1175);
WIRE 16 -1 (4850 1175)(5600 1175);
WIRE 16 -1 (4485 3425)(4650 3425);
WIRE 16 -1 (4850 3100)(4850 1175);
WIRE 16 -1 (4850 3100)(5750 3100);
FORCEPROP 2 LAST SIG_NAME V_BMC_LS_DDC_SDA_R
J 2
(5775 3110);
DISPLAY 0.808511 (5775 3110);
WIRE 16 -1 (1950 3700)(2075 3700);
WIRE 16 -1 (4485 3100)(4850 3100);
WIRE 16 -1 (4485 3425)(4485 3100);
WIRE 16 -1 (2075 3100)(4485 3100);
WIRE 16 -1 (2075 3700)(2075 3100);
WIRE 16 -1 (2075 3100)(875 3100);
WIRE 16 -1 (-825 3100)(875 3100);
WIRE 16 -1 (875 4150)(875 3100);
WIRE 16 -1 (875 4150)(1150 4150);
WIRE 16 -1 (975 4000)(1150 4000);
WIRE 16 -1 (1950 3750)(2150 3750);
WIRE 16 -1 (975 2325)(975 4000);
WIRE 16 -1 (725 2325)(975 2325);
WIRE 16 -1 (2150 2325)(975 2325);
WIRE 16 -1 (2150 2325)(2150 3750);
WIRE 16 -1 (4750 2325)(2150 2325);
WIRE 16 -1 (5775 2325)(4750 2325);
FORCEPROP 2 LAST SIG_NAME V_VGAHS_BUF
J 2
(5775 2335);
DISPLAY 0.808511 (5775 2335);
WIRE 16 -1 (4750 800)(4750 2325);
WIRE 16 -1 (525 2325)(-375 2325);
FORCEPROP 2 LAST SIG_NAME V_VGAHS_BUF_R
J 2
(390 2335);
DISPLAY 0.808511 (390 2335);
WIRE 16 -1 (5200 800)(5200 1075);
WIRE 16 -1 (4800 1075)(5200 1075);
WIRE 16 -1 (1950 3800)(2225 3800);
WIRE 16 -1 (4800 1075)(4800 2725);
WIRE 16 -1 (5775 2725)(4800 2725);
FORCEPROP 2 LAST SIG_NAME V_VGAVS_BUF
J 2
(5775 2735);
DISPLAY 0.808511 (5775 2735);
WIRE 16 -1 (4800 2725)(2225 2725);
WIRE 16 -1 (2225 2725)(2225 3800);
WIRE 16 -1 (2225 2725)(1075 2725);
WIRE 16 -1 (525 2725)(1075 2725);
WIRE 16 -1 (1075 3850)(1075 2725);
WIRE 16 -1 (1075 3850)(1150 3850);
WIRE 16 3135 (-1300 425)(1200 425);
WIRE 16 3135 (-1300 2075)(-1300 425);
WIRE 16 3135 (1200 425)(1200 2075);
WIRE 16 3135 (1200 2075)(-1300 2075);
WIRE 16 -1 (3700 3650)(3750 3650);
WIRE 16 -1 (2900 4300)(2550 4300);
WIRE 16 -1 (3750 3650)(3750 2000);
WIRE 16 -1 (3750 2000)(5775 2000);
FORCEPROP 2 LAST SIG_NAME V_DACB_IO
J 2
(5775 2010);
DISPLAY 0.808511 (5775 2010);
WIRE 16 -1 (2550 2000)(3750 2000);
WIRE 16 -1 (2550 4300)(2550 2000);
WIRE 16 -1 (1450 1175)(1450 2000);
WIRE 16 -1 (1450 2000)(2550 2000);
WIRE 16 -1 (975 1200)(975 2000);
WIRE 16 -1 (975 2000)(1450 2000);
WIRE 16 -1 (25 2000)(975 2000);
WIRE 16 -1 (3700 3750)(3900 3750);
WIRE 16 -1 (2900 4000)(2700 4000);
WIRE 16 -1 (3900 3750)(3900 1400);
WIRE 16 -1 (5775 1400)(3900 1400);
FORCEPROP 2 LAST SIG_NAME V_DACR_IO
J 2
(5775 1410);
DISPLAY 0.808511 (5775 1410);
WIRE 16 -1 (3900 1400)(2700 1400);
WIRE 16 -1 (2700 1400)(2700 4000);
WIRE 16 -1 (2525 1200)(2525 1400);
WIRE 16 -1 (2525 1400)(2700 1400);
WIRE 16 -1 (25 1400)(175 1400);
WIRE 16 -1 (175 1400)(2525 1400);
WIRE 16 -1 (175 1200)(175 1400);
WIRE 16 3135 (1125 1250)(75 1250);
WIRE 16 3135 (1125 1250)(1125 875);
WIRE 16 3135 (75 875)(75 1250);
WIRE 16 3135 (75 875)(1125 875);
WIRE 16 -1 (3700 3700)(3825 3700);
WIRE 16 -1 (2900 4150)(2625 4150);
WIRE 16 -1 (3825 1700)(3825 3700);
WIRE 16 -1 (3825 1700)(5775 1700);
FORCEPROP 2 LAST SIG_NAME V_DACG_IO
J 2
(5775 1710);
DISPLAY 0.808511 (5775 1710);
WIRE 16 -1 (2625 1700)(3825 1700);
WIRE 16 -1 (2625 4150)(2625 1700);
WIRE 16 -1 (2000 1200)(2000 1700);
WIRE 16 -1 (2000 1700)(2625 1700);
WIRE 16 -1 (575 1200)(575 1700);
WIRE 16 -1 (575 1700)(2000 1700);
WIRE 16 -1 (25 1700)(575 1700);
WIRE 16 -1 (975 1000)(975 750);
WIRE 16 -1 (175 1000)(175 750);
WIRE 16 -1 (100 -50)(-250 -50);
WIRE 16 -1 (100 -50)(100 -175);
WIRE 16 -1 (450 -525)(450 -50);
WIRE 16 -1 (450 -50)(100 -50);
FORCEPROP 2 LAST SIG_NAME V_BMC_DDC_LS_GATE
J 0
(-210 -40);
DISPLAY 0.808511 (-210 -40);
WIRE 16 3135 (-1250 900)(-1250 1250);
WIRE 16 3135 (-1250 900)(-200 900);
WIRE 16 3135 (-200 1250)(-1250 1250);
WIRE 16 3135 (-200 1250)(-200 900);
WIRE 16 -1 (2525 1000)(2525 800);
WIRE 16 -1 (1450 975)(1450 800);
WIRE 16 -1 (-775 2225)(-1475 2225);
WIRE 16 -1 (-1475 2625)(-1475 2225);
WIRE 16 -1 (-1475 2625)(-1175 2625);
WIRE 16 -1 (-775 2425)(-1550 2425);
FORCEPROP 2 LAST SIG_NAME BMC_DDC_BUF_PWR
J 0
(-1435 2435);
DISPLAY 0.808511 (-1435 2435);
WIRE 16 -1 (-1550 2825)(-1550 2425);
WIRE 16 -1 (-1550 2825)(-1175 2825);
WIRE 16 -1 (-1575 2825)(-1550 2825);
WIRE 16 -1 (-1150 975)(-1150 750);
WIRE 16 -1 (-425 750)(-425 975);
WIRE 16 -1 (1150 4300)(800 4300);
WIRE 16 -1 (1950 3650)(2000 3650);
WIRE 16 -1 (800 3300)(800 4300);
WIRE 16 -1 (-825 3300)(800 3300);
WIRE 16 -1 (4300 3575)(4775 3575);
WIRE 16 -1 (2000 3300)(800 3300);
WIRE 16 -1 (2000 3650)(2000 3300);
WIRE 16 -1 (4300 3300)(2000 3300);
WIRE 16 -1 (4300 3575)(4300 3300);
WIRE 16 -1 (4300 3300)(4900 3300);
WIRE 16 -1 (4900 3300)(5775 3300);
FORCEPROP 2 LAST SIG_NAME V_BMC_LS_DDC_SCL_R
J 2
(5775 3310);
DISPLAY 0.808511 (5775 3310);
WIRE 16 -1 (4900 1275)(4900 3300);
WIRE 16 -1 (4900 1275)(6000 1275);
WIRE 16 -1 (6000 800)(6000 1275);
WIRE 16 -1 (-425 1175)(-425 2000);
WIRE 16 -1 (-425 2000)(-175 2000);
WIRE 16 -1 (-1900 2000)(-425 2000);
FORCEPROP 2 LAST SIG_NAME V_DACB
J 0
(-1835 2010);
DISPLAY 0.808511 (-1835 2010);
WIRE 16 -1 (-1900 2325)(-875 2325);
FORCEPROP 2 LAST SIG_NAME V_VGAHS
J 0
(-1835 2335);
DISPLAY 0.808511 (-1835 2335);
WIRE 16 -1 (-1850 3100)(-1025 3100);
FORCEPROP 2 LAST SIG_NAME V_BMC_LS_DDC_SDA
J 0
(-1835 3110);
DISPLAY 0.808511 (-1835 3110);
WIRE 16 -1 (-1275 2725)(-1900 2725);
FORCEPROP 2 LAST SIG_NAME V_VGAVS
J 0
(-1835 2735);
DISPLAY 0.808511 (-1835 2735);
WIRE 16 -1 (-775 1175)(-775 1700);
WIRE 16 -1 (-775 1700)(-175 1700);
WIRE 16 -1 (-1900 1700)(-775 1700);
FORCEPROP 2 LAST SIG_NAME V_DACG
J 0
(-1835 1710);
DISPLAY 0.808511 (-1835 1710);
WIRE 16 -1 (-1150 1175)(-1150 1400);
WIRE 16 -1 (-175 1400)(-1150 1400);
WIRE 16 -1 (-1900 1400)(-1150 1400);
FORCEPROP 2 LAST SIG_NAME V_DACR
J 0
(-1835 1410);
DISPLAY 0.808511 (-1835 1410);
WIRE 16 -1 (-1875 450)(-1875 475);
WIRE 16 -1 (-2100 475)(-2100 450);
WIRE 16 -1 (-1875 450)(-2100 450);
WIRE 16 -1 (-2100 750)(-2100 675);
WIRE 16 -1 (-1875 750)(-1875 675);
WIRE 16 -1 (-1875 750)(-2100 750);
WIRE 16 3135 (1375 425)(2925 425);
WIRE 16 3135 (1375 2050)(1375 425);
WIRE 16 3135 (2925 425)(2925 2050);
WIRE 16 3135 (2925 2050)(1375 2050);
WIRE 16 -1 (5950 -225)(6025 -225);
WIRE 16 -1 (5950 -325)(6025 -325);
WIRE 16 -1 (5950 -325)(5950 -225);
WIRE 16 -1 (5950 -425)(5950 -325);
WIRE 16 -1 (5950 -425)(6025 -425);
WIRE 16 -1 (5950 -525)(6025 -525);
WIRE 16 -1 (5950 -525)(5950 -425);
WIRE 16 -1 (5950 -625)(5950 -525);
WIRE 16 -1 (5950 -625)(6025 -625);
WIRE 16 -1 (5950 -875)(6025 -875);
WIRE 16 -1 (5950 -625)(5950 -875);
WIRE 16 -1 (5950 -925)(5950 -875);
WIRE 16 -1 (5950 -925)(6025 -925);
WIRE 16 -1 (1950 4300)(2050 4300);
WIRE 16 -1 (3700 4300)(3800 4300);
WIRE 16 -1 (-1925 2825)(-1775 2825);
WIRE 16 -1 (-800 -100)(-800 0);
WIRE 16 -1 (-800 0)(-1100 0);
WIRE 16 -1 (-1100 0)(-1100 -100);
WIRE 16 -1 (-1775 4075)(-1425 4075);
WIRE 16 -1 (-1425 3975)(-1425 4075);
WIRE 16 -1 (-1425 4075)(-1425 4275);
WIRE 16 -1 (-1725 4275)(-1425 4275);
WIRE 16 -1 (-1425 4675)(-1425 4275);
WIRE 16 -1 (-1775 4675)(-1425 4675);
WIRE 16 -1 (-575 -50)(-450 -50);
WIRE 16 -1 (1025 -50)(1025 -100);
WIRE 16 -1 (5825 4675)(5825 4600);
WIRE 16 -1 (5825 4675)(5625 4675);
WIRE 16 -1 (6075 4675)(6075 4600);
WIRE 16 -1 (6075 4675)(5825 4675);
WIRE 16 -1 (6575 4675)(6575 4600);
WIRE 16 -1 (6325 4675)(6075 4675);
WIRE 16 -1 (6325 4675)(6325 4600);
WIRE 16 -1 (6325 4675)(6575 4675);
WIRE 16 -1 (5600 600)(5600 400);
WIRE 16 -1 (5200 400)(5600 400);
WIRE 16 -1 (5200 600)(5200 400);
WIRE 16 -1 (4750 400)(5200 400);
WIRE 16 -1 (4750 600)(4750 400);
WIRE 16 -1 (4975 3575)(5350 3575);
WIRE 16 -1 (5350 3425)(5350 3575);
WIRE 16 -1 (4850 3425)(5350 3425);
WIRE 16 -1 (-2175 4075)(-1975 4075);
WIRE 16 -1 (-2175 4075)(-2175 4275);
WIRE 16 -1 (-1975 4275)(-2175 4275);
WIRE 16 -1 (-2175 4675)(-2175 4275);
WIRE 16 -1 (-2175 4675)(-2025 4675);
WIRE 16 -1 (350 -425)(775 -425);
WIRE 16 -1 (2025 -425)(775 -425);
FORCEPROP 2 LAST SIG_NAME V_BMC_LS_DDC_SDA
J 0
(1190 -415);
DISPLAY 0.808511 (1190 -415);
WIRE 16 -1 (775 -300)(775 -425);
WIRE 16 -1 (700 -775)(1025 -775);
WIRE 16 -1 (2025 -775)(1025 -775);
WIRE 16 -1 (1025 -300)(1025 -775);
FORCEPROP 2 LAST SIG_NAME V_BMC_LS_DDC_SCL
J 0
(1190 -765);
DISPLAY 0.808511 (1190 -765);
WIRE 16 -1 (-800 -300)(-800 -775);
WIRE 16 -1 (-800 -775)(300 -775);
WIRE 16 -1 (-1725 -775)(-800 -775);
FORCEPROP 2 LAST SIG_NAME V_BMC_DDC_SCL
J 0
(-1710 -765);
DISPLAY 0.808511 (-1710 -765);
WIRE 16 -1 (5125 -175)(6025 -175);
FORCEPROP 2 LAST SIG_NAME V_DACR_IO
J 0
(5175 -165);
DISPLAY 0.808511 (5175 -165);
WIRE 16 -1 (5125 -275)(6025 -275);
FORCEPROP 2 LAST SIG_NAME V_DACG_IO
J 0
(5175 -265);
DISPLAY 0.808511 (5175 -265);
WIRE 16 -1 (5125 -375)(6025 -375);
FORCEPROP 2 LAST SIG_NAME V_DACB_IO
J 0
(5175 -365);
DISPLAY 0.808511 (5175 -365);
WIRE 16 -1 (6025 -475)(5125 -475);
FORCEPROP 2 LAST SIG_NAME V_VGAVS_BUF
J 0
(5175 -465);
DISPLAY 0.808511 (5175 -465);
WIRE 16 -1 (5125 -575)(6025 -575);
FORCEPROP 2 LAST SIG_NAME V_VGAHS_BUF
J 0
(5175 -565);
DISPLAY 0.808511 (5175 -565);
WIRE 16 -1 (5125 -675)(6025 -675);
FORCEPROP 2 LAST SIG_NAME V_BMC_LS_DDC_SDA_R
J 0
(5175 -665);
DISPLAY 0.808511 (5175 -665);
WIRE 16 -1 (5125 -725)(6025 -725);
FORCEPROP 2 LAST SIG_NAME V_BMC_LS_DDC_SCL_R
J 0
(5175 -715);
DISPLAY 0.808511 (5175 -715);
WIRE 16 -1 (4500 -775)(6025 -775);
FORCEPROP 2 LAST SIG_NAME CRT_VCC5_2_FUSE
J 0
(5165 -765);
DISPLAY 0.851064 (5165 -765);
WIRE 16 -1 (3550 -775)(4300 -775);
FORCEPROP 2 LAST SIG_NAME CRT_VCC5_2_D
J 0
(3665 -765);
DISPLAY 0.851064 (3665 -765);
WIRE 16 -1 (-1100 -300)(-1100 -425);
WIRE 16 -1 (-50 -425)(-1100 -425);
WIRE 16 -1 (-1725 -425)(-1100 -425);
FORCEPROP 2 LAST SIG_NAME V_BMC_DDC_SDA
J 0
(-1710 -415);
DISPLAY 0.808511 (-1710 -415);
WIRE 16 -1 (2775 3850)(2900 3850);
FORCEPROP 2 LAST SIG_NAME TP4
J 0
(2740 3860);
DISPLAY 0.808511 (2740 3860);
PAINT WHITE (2740 3860);
WIRE 16 -1 (15 2405)(15 2400);
WIRE 16 -1 (3700 3800)(4250 3800);
FORCEPROP 2 LAST SIG_NAME TP_ESD_VGA_P4
J 0
(3740 3810);
DISPLAY 0.808511 (3740 3810);
PAINT WHITE (3740 3810);
DOT 1 (1075 2725);
DOT 1 (575 750);
DOT 1 (175 1400);
DOT 1 (-1475 2225);
DOT 1 (-2100 750);
DOT 1 (-1150 1400);
DOT 1 (2000 800);
DOT 1 (2700 1400);
DOT 1 (775 -50);
DOT 1 (2525 1400);
DOT 1 (-775 750);
DOT 1 (5825 4675);
DOT 1 (6075 4675);
DOT 1 (6325 4675);
DOT 1 (4800 2725);
DOT 1 (4750 2325);
DOT 1 (-1425 4075);
DOT 1 (1025 -775);
DOT 1 (2150 2325);
DOT 1 (2225 2725);
DOT 1 (975 2000);
DOT 1 (-425 2000);
DOT 1 (4300 3300);
DOT 1 (-1100 0);
DOT 1 (1450 2000);
DOT 1 (2000 1700);
DOT 1 (575 1700);
DOT 1 (-1425 4675);
DOT 1 (-1425 4275);
DOT 1 (-2175 4675);
DOT 1 (-2175 4275);
DOT 1 (-1550 2825);
DOT 1 (-775 1700);
DOT 1 (-625 3000);
DOT 1 (-2100 450);
DOT 1 (-1100 -425);
DOT 1 (-800 -775);
DOT 1 (100 -50);
DOT 1 (775 -425);
DOT 1 (5950 -925);
DOT 1 (5950 -325);
DOT 1 (5600 400);
DOT 1 (5200 400);
DOT 1 (4900 3300);
DOT 1 (4850 3100);
DOT 1 (5350 3575);
DOT 1 (800 3300);
DOT 1 (2625 1700);
DOT 1 (3825 1700);
DOT 1 (3800 4150);
DOT 1 (2050 4150);
DOT 1 (4485 3100);
DOT 1 (3750 2000);
DOT 1 (875 3100);
DOT 1 (2550 2000);
DOT 1 (3900 1400);
DOT 1 (5950 -625);
DOT 1 (5950 -425);
DOT 1 (5950 -525);
DOT 1 (2075 3100);
DOT 1 (2000 3300);
DOT 1 (975 2325);
DOT 1 (6000 400);
DOT 1 (5950 -875);
FORCENOTE
CHANGE TO 22,18,22PF_20221221
(75 825) 0;
DISPLAY LEFT (75 825);
DISPLAY 1.021277 (75 825);
PAINT WHITE (75 825);
FORCENOTE
PLACE FILTER CIRCUIT CLOSE TO VGA CONN
(-1175 525) 0;
DISPLAY LEFT (-1175 525);
DISPLAY 1.276596 (-1175 525);
PAINT VIOLET (-1175 525);
FORCENOTE
DDC SMBUS ISOLATORS
(-2175 -1275) 0;
DISPLAY LEFT (-2175 -1275);
DISPLAY 3.148936 (-2175 -1275);
PAINT WHITE (-2175 -1275);
FORCENOTE
CHANGE TO 15PF_20221221
(-1250 825) 0;
DISPLAY LEFT (-1250 825);
DISPLAY 1.021277 (-1250 825);
PAINT WHITE (-1250 825);
FORCENOTE
CAD NOTE:
(-375 625) 0;
DISPLAY LEFT (-375 625);
DISPLAY 1.276596 (-375 625);
PAINT VIOLET (-375 625);
FORCENOTE
C5 CLOSE TO U1L2
(-1925 875) 0;
DISPLAY LEFT (-1925 875);
DISPLAY 0.638298 (-1925 875);
PAINT WHITE (-1925 875);
FORCENOTE
C6 CLOSE TO U1L3
(-1925 800) 0;
DISPLAY LEFT (-1925 800);
DISPLAY 0.638298 (-1925 800);
PAINT WHITE (-1925 800);
FORCENOTE
PLACE CLOSE TO VGA CONN
(1500 475) 0;
DISPLAY LEFT (1500 475);
DISPLAY 1.276596 (1500 475);
PAINT VIOLET (1500 475);
FORCENOTE
CAD NOTE:
(1500 550) 0;
DISPLAY LEFT (1500 550);
DISPLAY 1.276596 (1500 550);
PAINT VIOLET (1500 550);
FORCENOTE
R84,R85 CHANGE FROM 33 TO 0_20230314 
(450 2125) 0;
DISPLAY LEFT (450 2125);
DISPLAY 1.021277 (450 2125);
PAINT WHITE (450 2125);
QUIT
